FILE_TYPE = MACRO_DRAWING;
SET COLOR_WIRE YELLOW;
SET COLOR_PROP MONO;
SET COLOR_DOT WHITE;
SET COLOR_ARC YELLOW;
SET COLOR_BODY GREEN;
SET COLOR_NOTE MONO;
SET PROP_DISPLAY VALUE;
SET PAGE_NUMBER P215;
FORCEADD OFFPAGE..1
(-1400 675);
FORCEPROP 2 LAST $XR0 217 
J 0
(-1652 675);
DISPLAY 0.638298 (-1652 675);
PAINT MONO (-1652 675);
FORCEPROP 1 LAST COMMENT_BODY TRUE
J 0
(-1275 575);
DISPLAY 1.170213 (-1275 575);
PAINT GREEN (-1275 575);
DISPLAY INVISIBLE (-1275 575);
FORCEPROP 1 LAST OFFPAGE TRUE
J 0
(-1075 550);
DISPLAY 1.170213 (-1075 550);
PAINT GREEN (-1075 550);
DISPLAY INVISIBLE (-1075 550);
FORCEPROP 2 LAST PATH I1
J 0
(-1650 725);
DISPLAY 1.021277 (-1650 725);
PAINT ORANGE (-1650 725);
DISPLAY INVISIBLE (-1650 725);
FORCEPROP 2 LAST ROOM VDDQ_ABC_PWR_VR
J 0
(-1950 750);
DISPLAY 1.361702 (-1950 750);
PAINT ORANGE (-1950 750);
DISPLAY INVISIBLE (-1950 750);
FORCEPROP 2 LAST CDS_LIB mstr_standard
J 0
(-1400 675);
PAINT ORANGE (-1400 675);
DISPLAY INVISIBLE (-1400 675);
FORCEADD OFFPAGE..1
(-1400 2150);
FORCEPROP 2 LAST $XR0 216 
J 0
(-1652 2150);
DISPLAY 0.638298 (-1652 2150);
PAINT MONO (-1652 2150);
FORCEPROP 1 LAST COMMENT_BODY TRUE
J 0
(-1275 2050);
DISPLAY 1.170213 (-1275 2050);
PAINT GREEN (-1275 2050);
DISPLAY INVISIBLE (-1275 2050);
FORCEPROP 1 LAST OFFPAGE TRUE
J 0
(-1075 2025);
DISPLAY 1.170213 (-1075 2025);
PAINT GREEN (-1075 2025);
DISPLAY INVISIBLE (-1075 2025);
FORCEPROP 2 LAST PATH I10
J 0
(-1650 2200);
DISPLAY 1.021277 (-1650 2200);
PAINT ORANGE (-1650 2200);
DISPLAY INVISIBLE (-1650 2200);
FORCEPROP 2 LAST ROOM VDDQ_ABC_PWR_VR
J 0
(-1950 2225);
DISPLAY 1.361702 (-1950 2225);
PAINT ORANGE (-1950 2225);
DISPLAY INVISIBLE (-1950 2225);
FORCEPROP 2 LAST CDS_LIB mstr_standard
J 0
(-1400 2150);
PAINT ORANGE (-1400 2150);
DISPLAY INVISIBLE (-1400 2150);
FORCEADD OFFPAGE..1
(-1400 2800);
FORCEPROP 2 LAST $XR2 218 
J 0
(-1861 2800);
DISPLAY 0.638298 (-1861 2800);
PAINT MONO (-1861 2800);
FORCEPROP 2 LAST $XR1 194 
J 0
(-1741 2800);
DISPLAY 0.638298 (-1741 2800);
PAINT MONO (-1741 2800);
FORCEPROP 2 LAST $XR0 21 
J 0
(-1621 2800);
DISPLAY 0.638298 (-1621 2800);
PAINT MONO (-1621 2800);
FORCEPROP 1 LAST COMMENT_BODY TRUE
J 0
(-1275 2700);
DISPLAY 1.170213 (-1275 2700);
PAINT GREEN (-1275 2700);
DISPLAY INVISIBLE (-1275 2700);
FORCEPROP 1 LAST OFFPAGE TRUE
J 0
(-1075 2675);
DISPLAY 1.170213 (-1075 2675);
PAINT GREEN (-1075 2675);
DISPLAY INVISIBLE (-1075 2675);
FORCEPROP 2 LAST PATH I11
J 0
(-1600 2850);
DISPLAY 1.021277 (-1600 2850);
PAINT ORANGE (-1600 2850);
DISPLAY INVISIBLE (-1600 2850);
FORCEPROP 2 LAST ROOM VDDQ_ABC_PWR_VR
J 0
(-1950 2875);
DISPLAY 1.361702 (-1950 2875);
PAINT ORANGE (-1950 2875);
DISPLAY INVISIBLE (-1950 2875);
FORCEPROP 2 LAST CDS_LIB mstr_standard
J 0
(-1400 2800);
PAINT ORANGE (-1400 2800);
DISPLAY INVISIBLE (-1400 2800);
FORCEADD RES..1
(-575 1025);
FORCEPROP 1 LAST VALUE 10.0
J 2
(-675 925);
DISPLAY 0.617021 (-675 925);
PAINT SKYBLUE (-675 925);
FORCEPROP 1 LAST TOLERANCE 1%
J 0
(-650 925);
DISPLAY 0.617021 (-650 925);
PAINT SKYBLUE (-650 925);
FORCEPROP 1 LASTPIN (-675 1025) $PN 1
J 0
(-663 1037);
DISPLAY 0.617021 (-663 1037);
PAINT ORANGE (-663 1037);
FORCEPROP 1 LASTPIN (-475 1025) $PN 2
J 0
(-513 1037);
DISPLAY 0.617021 (-513 1037);
PAINT ORANGE (-513 1037);
FORCEPROP 1 LAST WATTAGE 1/16W
J 2
(-575 875);
DISPLAY 0.617021 (-575 875);
PAINT SKYBLUE (-575 875);
FORCEPROP 1 LAST LOCATION R7G9
J 0
(-625 1075);
DISPLAY 0.617021 (-625 1075);
PAINT AQUA (-625 1075);
FORCEPROP 1 LAST MATERIAL CHIP
J 0
(-550 875);
DISPLAY 0.617021 (-550 875);
PAINT SKYBLUE (-550 875);
FORCEPROP 1 LAST PACK_TYPE 0402
J 0
(-550 925);
DISPLAY 0.617021 (-550 925);
PAINT SKYBLUE (-550 925);
FORCEPROP 1 LAST PART_NUMBER G21796-066
J 0
(-725 975);
DISPLAY 0.617021 (-725 975);
PAINT BLUE (-725 975);
FORCEPROP 1 LAST PATH I12
J 0
(-625 1175);
DISPLAY 0.978723 (-625 1175);
PAINT WHITE (-625 1175);
DISPLAY INVISIBLE (-625 1175);
FORCEPROP 0 LAST CDS_SEC 1
J 0
(-625 1125);
PAINT MONO (-625 1125);
DISPLAY INVISIBLE (-625 1125);
FORCEPROP 2 LAST CDS_LOCATION R7G9
J 0
(-625 1075);
DISPLAY 0.617021 (-625 1075);
PAINT AQUA (-625 1075);
DISPLAY INVISIBLE (-625 1075);
FORCEPROP 2 LAST CDS_LIB mstr_discrete
J 0
(-575 1025);
PAINT ORANGE (-575 1025);
DISPLAY INVISIBLE (-575 1025);
FORCEPROP 2 LAST ROOM VDDQ_ABC_PWR_VR
J 0
(-500 1125);
DISPLAY 1.361702 (-500 1125);
PAINT ORANGE (-500 1125);
DISPLAY INVISIBLE (-500 1125);
FORCEPROP 2 LAST SEC_TYPE 0402
J 0
(-625 1250);
DISPLAY 1.021277 (-625 1250);
PAINT ORANGE (-625 1250);
DISPLAY INVISIBLE (-625 1250);
FORCEPROP 2 LAST SEC 1
J 0
(-625 1250);
DISPLAY 0.680851 (-625 1250);
PAINT MONO (-625 1250);
DISPLAY INVISIBLE (-625 1250);
FORCEPROP 2 LAST NO_XNET_CONNECTION 1
J 0
(-625 1250);
PAINT MONO (-625 1250);
DISPLAY INVISIBLE (-625 1250);
FORCEADD RES..1
(-425 1300);
FORCEPROP 1 LAST WATTAGE 1/16W
J 2
(-450 1150);
DISPLAY 0.617021 (-450 1150);
PAINT SKYBLUE (-450 1150);
FORCEPROP 1 LAST TOLERANCE 5%
J 0
(-475 1200);
DISPLAY 0.617021 (-475 1200);
PAINT SKYBLUE (-475 1200);
FORCEPROP 1 LAST VALUE 0.0
J 2
(-525 1200);
DISPLAY 0.617021 (-525 1200);
PAINT SKYBLUE (-525 1200);
FORCEPROP 1 LAST LOCATION R7F21
J 0
(-475 1350);
DISPLAY 0.617021 (-475 1350);
PAINT AQUA (-475 1350);
FORCEPROP 1 LAST PART_NUMBER G21497-005
J 0
(-575 1250);
DISPLAY 0.617021 (-575 1250);
PAINT BLUE (-575 1250);
FORCEPROP 1 LAST PACK_TYPE 0402
J 0
(-350 1200);
DISPLAY 0.617021 (-350 1200);
PAINT SKYBLUE (-350 1200);
FORCEPROP 1 LASTPIN (-325 1300) $PN 2
J 0
(-363 1312);
DISPLAY 0.787234 (-363 1312);
PAINT ORANGE (-363 1312);
FORCEPROP 1 LASTPIN (-525 1300) $PN 1
J 0
(-513 1312);
DISPLAY 0.787234 (-513 1312);
PAINT ORANGE (-513 1312);
FORCEPROP 1 LAST MATERIAL CHIP
J 0
(-425 1150);
DISPLAY 0.617021 (-425 1150);
PAINT SKYBLUE (-425 1150);
FORCEPROP 1 LAST PATH I13
J 0
(-475 1450);
DISPLAY 0.978723 (-475 1450);
PAINT WHITE (-475 1450);
DISPLAY INVISIBLE (-475 1450);
FORCEPROP 0 LAST CDS_SEC 1
J 0
(-475 1400);
PAINT MONO (-475 1400);
DISPLAY INVISIBLE (-475 1400);
FORCEPROP 2 LAST ROOM PVCCIN_CPU0_VR
J 0
(-475 1400);
DISPLAY 1.361702 (-475 1400);
PAINT ORANGE (-475 1400);
DISPLAY INVISIBLE (-475 1400);
FORCEPROP 2 LAST CDS_LOCATION R7F21
J 0
(-475 1350);
DISPLAY 0.617021 (-475 1350);
PAINT AQUA (-475 1350);
DISPLAY INVISIBLE (-475 1350);
FORCEPROP 2 LAST CDS_LIB mstr_discrete
J 0
(-425 1300);
PAINT ORANGE (-425 1300);
DISPLAY INVISIBLE (-425 1300);
FORCEPROP 2 LAST SEC 1
J 0
(-475 1500);
PAINT MONO (-475 1500);
DISPLAY INVISIBLE (-475 1500);
FORCEPROP 2 LAST SEC_TYPE 0402
J 0
(-475 1500);
DISPLAY 1.021277 (-475 1500);
PAINT ORANGE (-475 1500);
DISPLAY INVISIBLE (-475 1500);
FORCEADD CAP..1
(-300 850);
FORCEPROP 1 LASTPIN (-300 750) $PN 2
J 0
(-290 730);
DISPLAY 0.617021 (-290 730);
PAINT ORANGE (-290 730);
FORCEPROP 1 LASTPIN (-300 950) $PN 1
J 0
(-290 930);
DISPLAY 0.617021 (-290 930);
PAINT ORANGE (-290 930);
FORCEPROP 1 LAST VALUE 220PF
J 0
(-250 900);
DISPLAY 0.617021 (-250 900);
PAINT SKYBLUE (-250 900);
FORCEPROP 1 LAST TOLERANCE 10%
J 0
(-75 900);
DISPLAY 0.617021 (-75 900);
PAINT SKYBLUE (-75 900);
FORCEPROP 1 LAST MATERIAL X7R
J 0
(-125 850);
DISPLAY 0.617021 (-125 850);
PAINT SKYBLUE (-125 850);
FORCEPROP 1 LAST VOLTAGE 50V
J 0
(-250 850);
DISPLAY 0.617021 (-250 850);
PAINT SKYBLUE (-250 850);
FORCEPROP 1 LAST PART_NUMBER A36096-050
J 0
(-250 800);
DISPLAY 0.617021 (-250 800);
PAINT BLUE (-250 800);
FORCEPROP 1 LAST PACK_TYPE 0402LF
J 0
(-250 750);
DISPLAY 0.617021 (-250 750);
PAINT SKYBLUE (-250 750);
FORCEPROP 1 LAST LOCATION C7G4
J 0
(-250 950);
DISPLAY 0.617021 (-250 950);
PAINT AQUA (-250 950);
FORCEPROP 1 LAST PATH I14
J 0
(-250 1000);
DISPLAY 0.978723 (-250 1000);
PAINT WHITE (-250 1000);
DISPLAY INVISIBLE (-250 1000);
FORCEPROP 0 LAST CDS_SEC 1
J 0
(-250 1000);
PAINT MONO (-250 1000);
DISPLAY INVISIBLE (-250 1000);
FORCEPROP 2 LAST CDS_LOCATION C7G4
J 0
(-250 950);
DISPLAY 0.617021 (-250 950);
PAINT AQUA (-250 950);
DISPLAY INVISIBLE (-250 950);
FORCEPROP 2 LAST CDS_LIB mstr_discrete
J 0
(-300 850);
PAINT ORANGE (-300 850);
DISPLAY INVISIBLE (-300 850);
FORCEPROP 2 LAST NO_XNET_CONNECTION 1
J 0
(-250 1075);
PAINT MONO (-250 1075);
DISPLAY INVISIBLE (-250 1075);
FORCEPROP 2 LAST SEC_TYPE 0402LF
J 0
(-250 1075);
DISPLAY 1.021277 (-250 1075);
PAINT ORANGE (-250 1075);
DISPLAY INVISIBLE (-250 1075);
FORCEPROP 2 LAST SEC 1
J 0
(-250 1075);
DISPLAY 0.680851 (-250 1075);
PAINT MONO (-250 1075);
DISPLAY INVISIBLE (-250 1075);
FORCEPROP 2 LAST ROOM VDDQ_ABC_PWR_VR
J 0
(-250 1000);
DISPLAY 1.361702 (-250 1000);
PAINT ORANGE (-250 1000);
DISPLAY INVISIBLE (-250 1000);
FORCEADD RES..1
(-250 2525);
FORCEPROP 0 LAST GROUP POWER_FAIR
J 0
(-400 2475);
DISPLAY 0.638298 (-400 2475);
PAINT BROWN (-400 2475);
DISPLAY BOTH (-400 2475);
FORCEPROP 1 LAST PACK_TYPE 0402
J 0
(-175 2625);
DISPLAY 0.617021 (-175 2625);
PAINT SKYBLUE (-175 2625);
FORCEPROP 1 LAST MATERIAL CHIP
J 0
(-100 2525);
DISPLAY 0.617021 (-100 2525);
PAINT SKYBLUE (-100 2525);
FORCEPROP 1 LAST TOLERANCE 0.1%
J 0
(-200 2575);
DISPLAY 0.617021 (-200 2575);
PAINT SKYBLUE (-200 2575);
FORCEPROP 1 LASTPIN (-350 2525) $PN 1
J 0
(-338 2537);
DISPLAY 0.787234 (-338 2537);
PAINT ORANGE (-338 2537);
FORCEPROP 1 LASTPIN (-150 2525) $PN 2
J 0
(-188 2537);
DISPLAY 0.787234 (-188 2537);
PAINT ORANGE (-188 2537);
FORCEPROP 1 LAST LOCATION RF15
J 0
(-425 2575);
DISPLAY 0.617021 (-425 2575);
PAINT AQUA (-425 2575);
FORCEPROP 1 LAST WATTAGE 1/16W
J 2
(-350 2525);
DISPLAY 0.617021 (-350 2525);
PAINT SKYBLUE (-350 2525);
FORCEPROP 1 LAST PART_NUMBER G85996-004
J 0
(-400 2625);
DISPLAY 0.617021 (-400 2625);
PAINT BLUE (-400 2625);
FORCEPROP 1 LAST VALUE 1.0K
J 2
(-225 2575);
DISPLAY 0.617021 (-225 2575);
PAINT SKYBLUE (-225 2575);
FORCEPROP 0 LAST FAIR_SS 064.9090D.M001
J 0
(-400 2425);
DISPLAY 0.638298 (-400 2425);
PAINT BROWN (-400 2425);
DISPLAY BOTH (-400 2425);
FORCEPROP 2 LAST SEC_TYPE 0402
J 0
(-300 2725);
DISPLAY 1.021277 (-300 2725);
PAINT ORANGE (-300 2725);
DISPLAY INVISIBLE (-300 2725);
FORCEPROP 0 LAST SEC 1
J 0
(-175 2675);
DISPLAY 0.680851 (-175 2675);
PAINT MONO (-175 2675);
DISPLAY INVISIBLE (-175 2675);
FORCEPROP 0 LAST ROOM SB
J 0
(-200 2750);
DISPLAY 1.021277 (-200 2750);
PAINT ORANGE (-200 2750);
DISPLAY INVISIBLE (-200 2750);
FORCEPROP 2 LAST CDS_LIB mstr_discrete
J 0
(-250 2525);
PAINT MONO (-250 2525);
DISPLAY INVISIBLE (-250 2525);
FORCEPROP 0 LAST CDS_LOCATION RF15
J 0
(-175 2675);
PAINT MONO (-175 2675);
DISPLAY INVISIBLE (-175 2675);
FORCEPROP 0 LAST CDS_SEC 1
J 0
(-175 2675);
PAINT MONO (-175 2675);
DISPLAY INVISIBLE (-175 2675);
FORCEPROP 1 LAST PATH I15
J 0
(-300 2675);
DISPLAY 0.978723 (-300 2675);
PAINT WHITE (-300 2675);
DISPLAY INVISIBLE (-300 2675);
FORCEADD SC22P50V2JN-4GP..1
R 1
(-275 2325);
FORCEPROP 0 LAST GROUP POWER_FAIR
J 0
(-415 2240);
DISPLAY 0.638298 (-415 2240);
PAINT BROWN (-415 2240);
DISPLAY BOTH (-415 2240);
FORCEPROP 2 LAST ATTRIBUTE 22PF
J 0
(75 2375);
DISPLAY 0.638298 (75 2375);
PAINT GREEN (75 2375);
FORCEPROP 2 LAST RATED 50V
J 0
(75 2275);
DISPLAY 0.638298 (75 2275);
PAINT GREEN (75 2275);
FORCEPROP 2 LAST TYPE NPO
J 0
(200 2375);
DISPLAY 0.638298 (200 2375);
PAINT GREEN (200 2375);
FORCEPROP 0 LASTPIN (-350 2325) $PN 1
J 2
(-360 2335);
DISPLAY 0.808511 (-360 2335);
PAINT MONO (-360 2335);
FORCEPROP 0 LASTPIN (-200 2325) $PN 2
J 0
(-190 2335);
DISPLAY 0.808511 (-190 2335);
PAINT MONO (-190 2335);
FORCEPROP 2 LAST TOLERANCE 5%
J 0
(75 2325);
DISPLAY 0.638298 (75 2325);
PAINT GREEN (75 2325);
FORCEPROP 2 LAST PACK_SIZE 0402
J 0
(200 2325);
DISPLAY 0.638298 (200 2325);
PAINT GREEN (200 2325);
FORCEPROP 1 LAST LOCATION CF15
J 0
(-430 2375);
DISPLAY 0.617021 (-430 2375);
PAINT GREEN (-430 2375);
FORCEPROP 1 LAST VALUE SC22P50V2JN-4GP
J 0
(-300 2375);
DISPLAY 0.617021 (-300 2375);
PAINT GREEN (-300 2375);
FORCEPROP 1 LAST PART_NUMBER 78.22034.1FL
R 1
J 0
(-275 2325);
DISPLAY 0.617021 (-275 2325);
PAINT GREEN (-275 2325);
DISPLAY INVISIBLE (-275 2325);
FORCEPROP 1 LAST PACK_TYPE SMD-BCG
R 1
J 0
(-275 2325);
DISPLAY 0.617021 (-275 2325);
PAINT GREEN (-275 2325);
DISPLAY INVISIBLE (-275 2325);
FORCEPROP 1 LAST CDS_LMAN_SYM_OUTLINE -50,25,50,-25
R 1
J 0
(-275 2325);
DISPLAY 0.468085 (-275 2325);
PAINT GREEN (-275 2325);
DISPLAY INVISIBLE (-275 2325);
FORCEPROP 2 LAST CDS_LIB w_hdl
J 0
(-275 2325);
PAINT MONO (-275 2325);
DISPLAY INVISIBLE (-275 2325);
FORCEPROP 0 LAST CDS_LOCATION CF15
R 1
J 0
(-425 2425);
PAINT MONO (-425 2425);
DISPLAY INVISIBLE (-425 2425);
FORCEPROP 0 LAST $SEC 1
R 1
J 0
(-425 2425);
PAINT MONO (-425 2425);
DISPLAY INVISIBLE (-425 2425);
FORCEPROP 0 LAST CDS_SEC 1
R 1
J 0
(-425 2425);
PAINT MONO (-425 2425);
DISPLAY INVISIBLE (-425 2425);
FORCEPROP 1 LAST PATH I16
R 1
J 0
(-275 2325);
DISPLAY 0.617021 (-275 2325);
PAINT GREEN (-275 2325);
DISPLAY INVISIBLE (-275 2325);
FORCEADD PVCCIO_CPU0..1
(450 3600);
FORCEPROP 3 LASTPIN (450 3550) SIG_NAME PVCCIO_CPU0\g
J 0
(460 3560);
DISPLAY 0.659574 (460 3560);
PAINT MONO (460 3560);
DISPLAY INVISIBLE (460 3560);
FORCEPROP 1 LAST HDL_POWER PVCCIO_CPU0
J 1
(450 3650);
DISPLAY 0.872340 (450 3650);
PAINT GREEN (450 3650);
DISPLAY INVISIBLE (450 3650);
FORCEPROP 1 LAST BODY_TYPE PLUMBING
J 0
(405 3557);
DISPLAY 0.340426 (405 3557);
PAINT GREEN (405 3557);
DISPLAY INVISIBLE (405 3557);
FORCEPROP 1 LAST PATH I18
J 0
(500 3625);
DISPLAY 0.872340 (500 3625);
PAINT AQUA (500 3625);
DISPLAY INVISIBLE (500 3625);
FORCEPROP 2 LAST CDS_LIB mstr_symbols
J 0
(450 3600);
PAINT ORANGE (450 3600);
DISPLAY INVISIBLE (450 3600);
FORCEPROP 1 LAST VOLTAGE 1.1V
J 0
(405 3557);
DISPLAY 0.340426 (405 3557);
PAINT SKYBLUE (405 3557);
DISPLAY INVISIBLE (405 3557);
FORCEADD GND..1
(875 -150);
FORCEPROP 3 LASTPIN (875 -100) SIG_NAME GND\g
J 0
(885 -90);
DISPLAY 0.659574 (885 -90);
PAINT MONO (885 -90);
DISPLAY INVISIBLE (885 -90);
FORCEPROP 1 LAST HDL_POWER GND
J 0
(875 0);
DISPLAY 1.170213 (875 0);
PAINT GREEN (875 0);
DISPLAY INVISIBLE (875 0);
FORCEPROP 1 LAST BODY_TYPE PLUMBING
J 0
(830 -193);
DISPLAY 0.340426 (830 -193);
PAINT GREEN (830 -193);
DISPLAY INVISIBLE (830 -193);
FORCEPROP 1 LAST PATH I19
J 0
(950 -150);
DISPLAY 0.872340 (950 -150);
PAINT AQUA (950 -150);
DISPLAY INVISIBLE (950 -150);
FORCEPROP 2 LAST ROOM VDDQ_ABC_PWR_VR
J 0
(300 -75);
DISPLAY 1.361702 (300 -75);
PAINT ORANGE (300 -75);
DISPLAY INVISIBLE (300 -75);
FORCEPROP 1 LAST VOLTAGE 0
J 0
(875 -150);
PAINT SKYBLUE (875 -150);
DISPLAY INVISIBLE (875 -150);
FORCEPROP 2 LAST CDS_LIB mstr_symbols
J 0
(875 -150);
PAINT ORANGE (875 -150);
DISPLAY INVISIBLE (875 -150);
FORCEPROP 1 LAST SIZE 1B
J 0
(950 -200);
DISPLAY 1.170213 (950 -200);
PAINT AQUA (950 -200);
DISPLAY INVISIBLE (950 -200);
FORCEADD OFFPAGE..1
(-1400 1025);
FORCEPROP 2 LAST $XR0 217 
J 0
(-1652 1025);
DISPLAY 0.638298 (-1652 1025);
PAINT MONO (-1652 1025);
FORCEPROP 1 LAST COMMENT_BODY TRUE
J 0
(-1275 925);
DISPLAY 1.170213 (-1275 925);
PAINT GREEN (-1275 925);
DISPLAY INVISIBLE (-1275 925);
FORCEPROP 1 LAST OFFPAGE TRUE
J 0
(-1075 900);
DISPLAY 1.170213 (-1075 900);
PAINT GREEN (-1075 900);
DISPLAY INVISIBLE (-1075 900);
FORCEPROP 2 LAST PATH I2
J 0
(-1650 1075);
DISPLAY 1.021277 (-1650 1075);
PAINT ORANGE (-1650 1075);
DISPLAY INVISIBLE (-1650 1075);
FORCEPROP 2 LAST ROOM VDDQ_ABC_PWR_VR
J 0
(-1950 1100);
DISPLAY 1.361702 (-1950 1100);
PAINT ORANGE (-1950 1100);
DISPLAY INVISIBLE (-1950 1100);
FORCEPROP 2 LAST CDS_LIB mstr_standard
J 0
(-1400 1025);
PAINT ORANGE (-1400 1025);
DISPLAY INVISIBLE (-1400 1025);
FORCEADD GND..1
(1050 -300);
FORCEPROP 3 LASTPIN (1050 -250) SIG_NAME GND\g
J 0
(1060 -240);
DISPLAY 0.659574 (1060 -240);
PAINT MONO (1060 -240);
DISPLAY INVISIBLE (1060 -240);
FORCEPROP 1 LAST SIZE 1B
J 0
(1125 -350);
DISPLAY 1.170213 (1125 -350);
PAINT AQUA (1125 -350);
DISPLAY INVISIBLE (1125 -350);
FORCEPROP 1 LAST VOLTAGE 0
J 0
(1050 -300);
PAINT SKYBLUE (1050 -300);
DISPLAY INVISIBLE (1050 -300);
FORCEPROP 2 LAST CDS_LIB mstr_symbols
J 0
(1050 -300);
PAINT ORANGE (1050 -300);
DISPLAY INVISIBLE (1050 -300);
FORCEPROP 2 LAST ROOM VDDQ_ABC_PWR_VR
J 0
(475 -225);
DISPLAY 1.361702 (475 -225);
PAINT ORANGE (475 -225);
DISPLAY INVISIBLE (475 -225);
FORCEPROP 1 LAST PATH I20
J 0
(1125 -300);
DISPLAY 0.872340 (1125 -300);
PAINT AQUA (1125 -300);
DISPLAY INVISIBLE (1125 -300);
FORCEPROP 1 LAST BODY_TYPE PLUMBING
J 0
(1005 -343);
DISPLAY 0.340426 (1005 -343);
PAINT GREEN (1005 -343);
DISPLAY INVISIBLE (1005 -343);
FORCEPROP 1 LAST HDL_POWER GND
J 0
(1050 -150);
DISPLAY 1.170213 (1050 -150);
PAINT GREEN (1050 -150);
DISPLAY INVISIBLE (1050 -150);
FORCEADD CAP..1
R 2
(875 550);
FORCEPROP 1 LAST VOLTAGE 50V
J 2
(825 550);
DISPLAY 0.617021 (825 550);
PAINT SKYBLUE (825 550);
FORCEPROP 1 LAST LOCATION C7G3
J 2
(825 650);
DISPLAY 0.617021 (825 650);
PAINT AQUA (825 650);
FORCEPROP 1 LASTPIN (875 650) $PN 1
J 2
(865 630);
DISPLAY 0.617021 (865 630);
PAINT ORANGE (865 630);
FORCEPROP 1 LAST TOLERANCE 10%
J 2
(650 600);
DISPLAY 0.617021 (650 600);
PAINT SKYBLUE (650 600);
FORCEPROP 1 LAST MATERIAL X7R
J 2
(700 550);
DISPLAY 0.617021 (700 550);
PAINT SKYBLUE (700 550);
FORCEPROP 1 LAST PART_NUMBER A36096-050
J 2
(825 500);
DISPLAY 0.617021 (825 500);
PAINT BLUE (825 500);
FORCEPROP 1 LASTPIN (875 450) $PN 2
J 2
(865 430);
DISPLAY 0.617021 (865 430);
PAINT ORANGE (865 430);
FORCEPROP 1 LAST PACK_TYPE 0402LF
J 2
(825 450);
DISPLAY 0.617021 (825 450);
PAINT SKYBLUE (825 450);
FORCEPROP 1 LAST VALUE 220PF
J 2
(825 600);
DISPLAY 0.617021 (825 600);
PAINT SKYBLUE (825 600);
FORCEPROP 1 LAST PATH I22
J 2
(825 700);
DISPLAY 0.978723 (825 700);
PAINT WHITE (825 700);
DISPLAY INVISIBLE (825 700);
FORCEPROP 0 LAST CDS_SEC 1
J 0
(825 700);
PAINT MONO (825 700);
DISPLAY INVISIBLE (825 700);
FORCEPROP 2 LAST CDS_LIB mstr_discrete
J 2
(875 550);
PAINT ORANGE (875 550);
DISPLAY INVISIBLE (875 550);
FORCEPROP 2 LAST CDS_LOCATION C7G3
J 2
(825 650);
DISPLAY 0.617021 (825 650);
PAINT AQUA (825 650);
DISPLAY INVISIBLE (825 650);
FORCEPROP 2 LAST ROOM VDDQ_ABC_PWR_VR
J 2
(825 700);
DISPLAY 1.361702 (825 700);
PAINT ORANGE (825 700);
DISPLAY INVISIBLE (825 700);
FORCEPROP 2 LAST SEC 1
J 2
(825 775);
DISPLAY 0.680851 (825 775);
PAINT MONO (825 775);
DISPLAY INVISIBLE (825 775);
FORCEPROP 2 LAST SEC_TYPE 0402LF
J 2
(825 775);
DISPLAY 1.021277 (825 775);
PAINT ORANGE (825 775);
DISPLAY INVISIBLE (825 775);
FORCEADD GND..1
(950 650);
FORCEPROP 3 LASTPIN (950 700) SIG_NAME GND\g
J 0
(960 710);
DISPLAY 0.659574 (960 710);
PAINT MONO (960 710);
DISPLAY INVISIBLE (960 710);
FORCEPROP 1 LAST HDL_POWER GND
J 0
(950 800);
DISPLAY 1.170213 (950 800);
PAINT GREEN (950 800);
DISPLAY INVISIBLE (950 800);
FORCEPROP 1 LAST BODY_TYPE PLUMBING
J 0
(905 607);
DISPLAY 0.340426 (905 607);
PAINT GREEN (905 607);
DISPLAY INVISIBLE (905 607);
FORCEPROP 1 LAST PATH I23
J 0
(1025 650);
DISPLAY 0.872340 (1025 650);
PAINT AQUA (1025 650);
DISPLAY INVISIBLE (1025 650);
FORCEPROP 2 LAST ROOM VDDQ_ABC_PWR_VR
J 0
(375 725);
DISPLAY 1.361702 (375 725);
PAINT ORANGE (375 725);
DISPLAY INVISIBLE (375 725);
FORCEPROP 1 LAST SIZE 1B
J 0
(1025 600);
DISPLAY 1.170213 (1025 600);
PAINT AQUA (1025 600);
DISPLAY INVISIBLE (1025 600);
FORCEPROP 2 LAST CDS_LIB mstr_symbols
J 0
(950 650);
PAINT ORANGE (950 650);
DISPLAY INVISIBLE (950 650);
FORCEPROP 1 LAST VOLTAGE 0
J 0
(950 650);
PAINT SKYBLUE (950 650);
DISPLAY INVISIBLE (950 650);
FORCEADD GND..1
(1400 -300);
FORCEPROP 3 LASTPIN (1400 -250) SIG_NAME GND\g
J 0
(1410 -240);
DISPLAY 0.659574 (1410 -240);
PAINT MONO (1410 -240);
DISPLAY INVISIBLE (1410 -240);
FORCEPROP 1 LAST VOLTAGE 0
J 0
(1400 -300);
PAINT SKYBLUE (1400 -300);
DISPLAY INVISIBLE (1400 -300);
FORCEPROP 2 LAST CDS_LIB mstr_symbols
J 0
(1400 -300);
PAINT ORANGE (1400 -300);
DISPLAY INVISIBLE (1400 -300);
FORCEPROP 1 LAST SIZE 1B
J 0
(1475 -350);
DISPLAY 1.170213 (1475 -350);
PAINT AQUA (1475 -350);
DISPLAY INVISIBLE (1475 -350);
FORCEPROP 2 LAST ROOM VDDQ_ABC_PWR_VR
J 0
(825 -225);
DISPLAY 1.361702 (825 -225);
PAINT ORANGE (825 -225);
DISPLAY INVISIBLE (825 -225);
FORCEPROP 1 LAST PATH I24
J 0
(1475 -300);
DISPLAY 0.872340 (1475 -300);
PAINT AQUA (1475 -300);
DISPLAY INVISIBLE (1475 -300);
FORCEPROP 1 LAST BODY_TYPE PLUMBING
J 0
(1355 -343);
DISPLAY 0.340426 (1355 -343);
PAINT GREEN (1355 -343);
DISPLAY INVISIBLE (1355 -343);
FORCEPROP 1 LAST HDL_POWER GND
J 0
(1400 -150);
DISPLAY 1.170213 (1400 -150);
PAINT GREEN (1400 -150);
DISPLAY INVISIBLE (1400 -150);
FORCEADD SC22P50V2JN-4GP..1
R 1
(625 2450);
FORCEPROP 2 LAST TOLERANCE 5%
J 0
(625 2175);
DISPLAY 0.638298 (625 2175);
PAINT GREEN (625 2175);
FORCEPROP 2 LAST TYPE NPO
J 0
(475 2125);
DISPLAY 0.638298 (475 2125);
PAINT GREEN (475 2125);
FORCEPROP 2 LAST ATTRIBUTE 22PF
J 0
(475 2175);
DISPLAY 0.638298 (475 2175);
PAINT GREEN (475 2175);
FORCEPROP 1 LAST LOCATION CF16
J 0
(470 2275);
DISPLAY 0.617021 (470 2275);
PAINT GREEN (470 2275);
FORCEPROP 2 LAST PACK_SIZE 0402
J 0
(625 2125);
DISPLAY 0.638298 (625 2125);
PAINT GREEN (625 2125);
FORCEPROP 2 LAST RATED 50V
J 0
(725 2175);
DISPLAY 0.638298 (725 2175);
PAINT GREEN (725 2175);
FORCEPROP 0 LASTPIN (550 2450) $PN 1
J 2
(540 2460);
DISPLAY 0.808511 (540 2460);
PAINT MONO (540 2460);
FORCEPROP 1 LAST VALUE SC22P50V2JN-4GP
J 0
(475 2225);
DISPLAY 0.617021 (475 2225);
PAINT GREEN (475 2225);
FORCEPROP 0 LAST BOM_SS NOPOP
J 0
(475 2325);
DISPLAY 0.638298 (475 2325);
PAINT BROWN (475 2325);
DISPLAY BOTH (475 2325);
FORCEPROP 0 LAST GROUP POWER_FAIR
J 0
(460 2365);
DISPLAY 0.638298 (460 2365);
PAINT BROWN (460 2365);
DISPLAY BOTH (460 2365);
FORCEPROP 0 LASTPIN (700 2450) $PN 2
J 0
(710 2460);
DISPLAY 0.808511 (710 2460);
PAINT MONO (710 2460);
FORCEPROP 1 LAST PACK_TYPE SMD-BCG
R 1
J 0
(625 2450);
DISPLAY 0.617021 (625 2450);
PAINT GREEN (625 2450);
DISPLAY INVISIBLE (625 2450);
FORCEPROP 1 LAST PART_NUMBER 78.22034.1FL
R 1
J 0
(625 2450);
DISPLAY 0.617021 (625 2450);
PAINT GREEN (625 2450);
DISPLAY INVISIBLE (625 2450);
FORCEPROP 1 LAST CDS_LMAN_SYM_OUTLINE -50,25,50,-25
R 1
J 0
(625 2450);
DISPLAY 0.468085 (625 2450);
PAINT GREEN (625 2450);
DISPLAY INVISIBLE (625 2450);
FORCEPROP 2 LAST CDS_LIB w_hdl
J 0
(625 2450);
PAINT MONO (625 2450);
DISPLAY INVISIBLE (625 2450);
FORCEPROP 0 LAST CDS_LOCATION CF16
R 1
J 0
(450 2600);
PAINT MONO (450 2600);
DISPLAY INVISIBLE (450 2600);
FORCEPROP 0 LAST $SEC 1
R 1
J 0
(450 2600);
PAINT MONO (450 2600);
DISPLAY INVISIBLE (450 2600);
FORCEPROP 0 LAST CDS_SEC 1
R 1
J 0
(450 2600);
PAINT MONO (450 2600);
DISPLAY INVISIBLE (450 2600);
FORCEPROP 1 LAST PATH I26
R 1
J 0
(625 2450);
DISPLAY 0.617021 (625 2450);
PAINT GREEN (625 2450);
DISPLAY INVISIBLE (625 2450);
FORCEADD RES..1
(650 2600);
FORCEPROP 1 LAST LOCATION RF16
J 0
(475 2650);
DISPLAY 0.617021 (475 2650);
PAINT AQUA (475 2650);
FORCEPROP 1 LAST WATTAGE 1/16W
J 2
(900 2650);
DISPLAY 0.617021 (900 2650);
PAINT SKYBLUE (900 2650);
FORCEPROP 1 LAST MATERIAL CHIP
J 0
(825 2700);
DISPLAY 0.617021 (825 2700);
PAINT SKYBLUE (825 2700);
FORCEPROP 1 LAST PACK_TYPE 0402
J 0
(725 2700);
DISPLAY 0.617021 (725 2700);
PAINT SKYBLUE (725 2700);
FORCEPROP 1 LASTPIN (550 2600) $PN 1
J 0
(562 2612);
DISPLAY 0.787234 (562 2612);
PAINT ORANGE (562 2612);
FORCEPROP 1 LASTPIN (750 2600) $PN 2
J 0
(712 2612);
DISPLAY 0.787234 (712 2612);
PAINT ORANGE (712 2612);
FORCEPROP 1 LAST TOLERANCE 0.1%
J 0
(700 2650);
DISPLAY 0.617021 (700 2650);
PAINT SKYBLUE (700 2650);
FORCEPROP 1 LAST PART_NUMBER G85996-004
J 0
(500 2700);
DISPLAY 0.617021 (500 2700);
PAINT BLUE (500 2700);
FORCEPROP 1 LAST VALUE 1.0K
J 2
(675 2650);
DISPLAY 0.617021 (675 2650);
PAINT SKYBLUE (675 2650);
FORCEPROP 0 LAST GROUP POWER_FAIR
J 0
(475 2550);
DISPLAY 0.638298 (475 2550);
PAINT BROWN (475 2550);
DISPLAY BOTH (475 2550);
FORCEPROP 0 LAST BOM_SS NOPOP
J 0
(475 2500);
DISPLAY 0.638298 (475 2500);
PAINT BROWN (475 2500);
DISPLAY BOTH (475 2500);
FORCEPROP 1 LAST PATH I27
J 0
(600 2750);
DISPLAY 0.978723 (600 2750);
PAINT WHITE (600 2750);
DISPLAY INVISIBLE (600 2750);
FORCEPROP 0 LAST CDS_SEC 1
J 0
(825 2750);
PAINT MONO (825 2750);
DISPLAY INVISIBLE (825 2750);
FORCEPROP 0 LAST CDS_LOCATION RF16
J 0
(825 2750);
PAINT MONO (825 2750);
DISPLAY INVISIBLE (825 2750);
FORCEPROP 2 LAST CDS_LIB mstr_discrete
J 0
(650 2600);
PAINT MONO (650 2600);
DISPLAY INVISIBLE (650 2600);
FORCEPROP 0 LAST ROOM SB
J 0
(700 2825);
DISPLAY 1.021277 (700 2825);
PAINT ORANGE (700 2825);
DISPLAY INVISIBLE (700 2825);
FORCEPROP 0 LAST SEC 1
J 0
(725 2750);
DISPLAY 0.680851 (725 2750);
PAINT MONO (725 2750);
DISPLAY INVISIBLE (725 2750);
FORCEPROP 2 LAST SEC_TYPE 0402
J 0
(600 2800);
DISPLAY 1.021277 (600 2800);
PAINT ORANGE (600 2800);
DISPLAY INVISIBLE (600 2800);
FORCEADD RES..1
(675 2800);
FORCEPROP 1 LASTPIN (575 2800) $PN 1
J 0
(587 2812);
DISPLAY 0.617021 (587 2812);
PAINT ORANGE (587 2812);
FORCEPROP 1 LASTPIN (775 2800) $PN 2
J 0
(737 2812);
DISPLAY 0.617021 (737 2812);
PAINT ORANGE (737 2812);
FORCEPROP 1 LAST TOLERANCE 1%
J 0
(725 2875);
DISPLAY 0.617021 (725 2875);
PAINT SKYBLUE (725 2875);
FORCEPROP 1 LAST PACK_TYPE 0402
J 0
(850 2875);
DISPLAY 0.617021 (850 2875);
PAINT SKYBLUE (850 2875);
FORCEPROP 1 LAST MATERIAL CHIP
J 0
(775 2825);
DISPLAY 0.617021 (775 2825);
PAINT SKYBLUE (775 2825);
FORCEPROP 1 LAST LOCATION R7G24
J 0
(575 2975);
DISPLAY 0.617021 (575 2975);
PAINT AQUA (575 2975);
FORCEPROP 1 LAST PART_NUMBER G21796-009
J 0
(575 2925);
DISPLAY 0.617021 (575 2925);
PAINT BLUE (575 2925);
FORCEPROP 1 LAST VALUE 150.0
J 2
(675 2875);
DISPLAY 0.617021 (675 2875);
PAINT SKYBLUE (675 2875);
FORCEPROP 1 LAST WATTAGE 1/16W
J 2
(725 2825);
DISPLAY 0.617021 (725 2825);
PAINT SKYBLUE (725 2825);
FORCEPROP 1 LAST PATH I28
J 0
(625 2950);
DISPLAY 0.978723 (625 2950);
PAINT WHITE (625 2950);
DISPLAY INVISIBLE (625 2950);
FORCEPROP 0 LAST CDS_SEC 1
J 0
(575 3025);
PAINT MONO (575 3025);
DISPLAY INVISIBLE (575 3025);
FORCEPROP 0 LAST CDS_LOCATION R7G24
J 0
(575 3025);
PAINT MONO (575 3025);
DISPLAY INVISIBLE (575 3025);
FORCEPROP 2 LAST CDS_LIB mstr_discrete
J 0
(675 2800);
PAINT ORANGE (675 2800);
DISPLAY INVISIBLE (675 2800);
FORCEPROP 2 LAST SEC_TYPE 0402
J 0
(625 3025);
DISPLAY 1.021277 (625 3025);
PAINT ORANGE (625 3025);
DISPLAY INVISIBLE (625 3025);
FORCEPROP 2 LAST SEC 1
J 0
(625 3025);
DISPLAY 0.680851 (625 3025);
PAINT MONO (625 3025);
DISPLAY INVISIBLE (625 3025);
FORCEPROP 2 LAST ROOM VDDQ_ABC_PWR_VR
J 0
(575 3025);
DISPLAY 1.361702 (575 3025);
PAINT ORANGE (575 3025);
DISPLAY INVISIBLE (575 3025);
FORCEADD RES..2
(975 3325);
FORCEPROP 1 LASTPIN (975 3225) $PN 2
J 0
(980 3235);
DISPLAY 0.787234 (980 3235);
PAINT ORANGE (980 3235);
FORCEPROP 1 LAST PART_NUMBER G21796-010
J 0
(1015 3200);
DISPLAY 0.617021 (1015 3200);
PAINT BLUE (1015 3200);
FORCEPROP 1 LAST PACK_TYPE 0402
J 0
(1015 3150);
DISPLAY 0.617021 (1015 3150);
PAINT SKYBLUE (1015 3150);
FORCEPROP 1 LAST MATERIAL EMPTY
J 0
(1015 3250);
DISPLAY 0.617021 (1015 3250);
PAINT RED (1015 3250);
FORCEPROP 1 LAST TOLERANCE 1%
J 0
(1020 3350);
DISPLAY 0.617021 (1020 3350);
PAINT SKYBLUE (1020 3350);
FORCEPROP 1 LAST WATTAGE 1/16W
J 0
(1015 3300);
DISPLAY 0.617021 (1015 3300);
PAINT SKYBLUE (1015 3300);
FORCEPROP 1 LASTPIN (975 3425) $PN 1
J 0
(980 3387);
DISPLAY 0.787234 (980 3387);
PAINT ORANGE (980 3387);
FORCEPROP 1 LAST VALUE 100.0K
J 0
(1020 3400);
DISPLAY 0.617021 (1020 3400);
PAINT SKYBLUE (1020 3400);
FORCEPROP 1 LAST LOCATION R7F20
J 0
(1020 3450);
DISPLAY 0.617021 (1020 3450);
PAINT AQUA (1020 3450);
FORCEPROP 1 LAST PATH I29
J 0
(1025 3500);
DISPLAY 0.978723 (1025 3500);
PAINT WHITE (1025 3500);
DISPLAY INVISIBLE (1025 3500);
FORCEPROP 0 LAST CDS_SEC 1
J 0
(1025 3500);
PAINT MONO (1025 3500);
DISPLAY INVISIBLE (1025 3500);
FORCEPROP 2 LAST CDS_LIB mstr_discrete
J 0
(975 3325);
PAINT ORANGE (975 3325);
DISPLAY INVISIBLE (975 3325);
FORCEPROP 2 LAST CDS_LOCATION R7F20
J 0
(1020 3450);
DISPLAY 0.617021 (1020 3450);
PAINT AQUA (1020 3450);
DISPLAY INVISIBLE (1020 3450);
FORCEPROP 0 LAST ROOM BMC
J 0
(1025 3550);
DISPLAY 0.617021 (1025 3550);
PAINT ORANGE (1025 3550);
DISPLAY INVISIBLE (1025 3550);
FORCEPROP 0 LAST BOM_COST SM_CONTROLLER
J 0
(1025 3650);
DISPLAY 1.021277 (1025 3650);
PAINT ORANGE (1025 3650);
DISPLAY INVISIBLE (1025 3650);
FORCEPROP 2 LAST SEC 1
J 0
(1025 3550);
PAINT MONO (1025 3550);
DISPLAY INVISIBLE (1025 3550);
FORCEPROP 2 LAST SEC_TYPE 0402
J 0
(1025 3550);
DISPLAY 1.021277 (1025 3550);
PAINT ORANGE (1025 3550);
DISPLAY INVISIBLE (1025 3550);
FORCEADD OFFPAGE..1
(-1400 1300);
FORCEPROP 2 LAST $XR0 191 
J 0
(-1652 1300);
DISPLAY 0.638298 (-1652 1300);
PAINT MONO (-1652 1300);
FORCEPROP 1 LAST COMMENT_BODY TRUE
J 0
(-1275 1200);
DISPLAY 1.170213 (-1275 1200);
PAINT GREEN (-1275 1200);
DISPLAY INVISIBLE (-1275 1200);
FORCEPROP 1 LAST OFFPAGE TRUE
J 0
(-1075 1175);
DISPLAY 1.170213 (-1075 1175);
PAINT GREEN (-1075 1175);
DISPLAY INVISIBLE (-1075 1175);
FORCEPROP 2 LAST PATH I3
J 0
(-1650 1350);
DISPLAY 1.021277 (-1650 1350);
PAINT ORANGE (-1650 1350);
DISPLAY INVISIBLE (-1650 1350);
FORCEPROP 2 LAST ROOM VDDQ_ABC_PWR_VR
J 0
(-1950 1375);
DISPLAY 1.361702 (-1950 1375);
PAINT ORANGE (-1950 1375);
DISPLAY INVISIBLE (-1950 1375);
FORCEPROP 2 LAST CDS_LIB mstr_standard
J 0
(-1400 1300);
PAINT ORANGE (-1400 1300);
DISPLAY INVISIBLE (-1400 1300);
FORCEADD P3V3_STBY..1
(1675 3675);
FORCEPROP 3 LASTPIN (1675 3625) SIG_NAME P3V3_STBY\g
J 0
(1685 3635);
DISPLAY 0.659574 (1685 3635);
PAINT MONO (1685 3635);
DISPLAY INVISIBLE (1685 3635);
FORCEPROP 1 LAST HDL_POWER P3V3_STBY
J 0
(1375 3550);
DISPLAY 0.872340 (1375 3550);
PAINT ORANGE (1375 3550);
DISPLAY INVISIBLE (1375 3550);
FORCEPROP 1 LAST BODY_TYPE PLUMBING
J 0
(1630 3632);
DISPLAY 0.340426 (1630 3632);
PAINT GREEN (1630 3632);
DISPLAY INVISIBLE (1630 3632);
FORCEPROP 1 LAST PATH I30
J 0
(1720 3677);
DISPLAY 0.340426 (1720 3677);
PAINT GREEN (1720 3677);
DISPLAY INVISIBLE (1720 3677);
FORCEPROP 1 LAST VOLTAGE 3.3V
J 0
(1630 3632);
DISPLAY 0.340426 (1630 3632);
PAINT SKYBLUE (1630 3632);
DISPLAY INVISIBLE (1630 3632);
FORCEPROP 2 LAST CDS_LIB mstr_symbols
J 0
(1675 3675);
PAINT ORANGE (1675 3675);
DISPLAY INVISIBLE (1675 3675);
FORCEPROP 1 LAST SIZE 1B
J 0
(1720 3697);
DISPLAY 0.340426 (1720 3697);
PAINT GREEN (1720 3697);
DISPLAY INVISIBLE (1720 3697);
FORCEADD GND..1
(1975 2700);
FORCEPROP 3 LASTPIN (1975 2750) SIG_NAME GND\g
J 0
(1985 2760);
DISPLAY 0.659574 (1985 2760);
PAINT MONO (1985 2760);
DISPLAY INVISIBLE (1985 2760);
FORCEPROP 1 LAST HDL_POWER GND
J 0
(1975 2850);
DISPLAY 1.170213 (1975 2850);
PAINT GREEN (1975 2850);
DISPLAY INVISIBLE (1975 2850);
FORCEPROP 1 LAST BODY_TYPE PLUMBING
J 0
(1930 2657);
DISPLAY 0.340426 (1930 2657);
PAINT GREEN (1930 2657);
DISPLAY INVISIBLE (1930 2657);
FORCEPROP 1 LAST PATH I31
J 0
(2050 2700);
DISPLAY 0.872340 (2050 2700);
PAINT AQUA (2050 2700);
DISPLAY INVISIBLE (2050 2700);
FORCEPROP 2 LAST ROOM VDDQ_ABC_PWR_VR
J 0
(1400 2775);
DISPLAY 1.361702 (1400 2775);
PAINT ORANGE (1400 2775);
DISPLAY INVISIBLE (1400 2775);
FORCEPROP 2 LAST CDS_LIB mstr_symbols
J 0
(1975 2700);
PAINT ORANGE (1975 2700);
DISPLAY INVISIBLE (1975 2700);
FORCEPROP 1 LAST SIZE 1B
J 0
(2050 2650);
DISPLAY 1.170213 (2050 2650);
PAINT AQUA (2050 2650);
DISPLAY INVISIBLE (2050 2650);
FORCEPROP 1 LAST VOLTAGE 0
J 0
(1975 2700);
PAINT SKYBLUE (1975 2700);
DISPLAY INVISIBLE (1975 2700);
FORCEADD GND..1
(2375 2700);
FORCEPROP 3 LASTPIN (2375 2750) SIG_NAME GND\g
J 0
(2385 2760);
DISPLAY 0.659574 (2385 2760);
PAINT MONO (2385 2760);
DISPLAY INVISIBLE (2385 2760);
FORCEPROP 1 LAST HDL_POWER GND
J 0
(2375 2850);
DISPLAY 1.170213 (2375 2850);
PAINT GREEN (2375 2850);
DISPLAY INVISIBLE (2375 2850);
FORCEPROP 1 LAST BODY_TYPE PLUMBING
J 0
(2330 2657);
DISPLAY 0.340426 (2330 2657);
PAINT GREEN (2330 2657);
DISPLAY INVISIBLE (2330 2657);
FORCEPROP 1 LAST PATH I32
J 0
(2450 2700);
DISPLAY 0.872340 (2450 2700);
PAINT AQUA (2450 2700);
DISPLAY INVISIBLE (2450 2700);
FORCEPROP 1 LAST VOLTAGE 0
J 0
(2375 2700);
PAINT SKYBLUE (2375 2700);
DISPLAY INVISIBLE (2375 2700);
FORCEPROP 1 LAST SIZE 1B
J 0
(2450 2650);
DISPLAY 1.170213 (2450 2650);
PAINT AQUA (2450 2650);
DISPLAY INVISIBLE (2450 2650);
FORCEPROP 2 LAST CDS_LIB mstr_symbols
J 0
(2375 2700);
PAINT ORANGE (2375 2700);
DISPLAY INVISIBLE (2375 2700);
FORCEPROP 2 LAST ROOM VDDQ_ABC_PWR_VR
J 0
(1800 2775);
DISPLAY 1.361702 (1800 2775);
PAINT ORANGE (1800 2775);
DISPLAY INVISIBLE (1800 2775);
FORCEADD RES..2
(1675 3250);
FORCEPROP 1 LASTPIN (1675 3150) $PN 2
J 0
(1680 3160);
DISPLAY 0.617021 (1680 3160);
PAINT ORANGE (1680 3160);
FORCEPROP 1 LAST MATERIAL CHIP
J 0
(1715 3175);
DISPLAY 0.617021 (1715 3175);
PAINT SKYBLUE (1715 3175);
FORCEPROP 1 LAST PACK_TYPE 0402
J 0
(1715 3075);
DISPLAY 0.617021 (1715 3075);
PAINT SKYBLUE (1715 3075);
FORCEPROP 1 LAST PART_NUMBER G21497-005
J 0
(1715 3125);
DISPLAY 0.617021 (1715 3125);
PAINT BLUE (1715 3125);
FORCEPROP 1 LAST WATTAGE 1/16W
J 0
(1715 3225);
DISPLAY 0.617021 (1715 3225);
PAINT SKYBLUE (1715 3225);
FORCEPROP 1 LAST TOLERANCE 5%
J 0
(1720 3275);
DISPLAY 0.617021 (1720 3275);
PAINT SKYBLUE (1720 3275);
FORCEPROP 1 LASTPIN (1675 3350) $PN 1
J 0
(1680 3312);
DISPLAY 0.617021 (1680 3312);
PAINT ORANGE (1680 3312);
FORCEPROP 1 LAST VALUE 0.0
J 0
(1720 3325);
DISPLAY 0.617021 (1720 3325);
PAINT SKYBLUE (1720 3325);
FORCEPROP 1 LAST LOCATION R3T13
J 0
(1720 3375);
DISPLAY 0.617021 (1720 3375);
PAINT AQUA (1720 3375);
FORCEPROP 1 LAST PATH I33
J 0
(1725 3425);
DISPLAY 0.978723 (1725 3425);
PAINT WHITE (1725 3425);
DISPLAY INVISIBLE (1725 3425);
FORCEPROP 0 LAST CDS_SEC 1
J 0
(1725 3425);
PAINT MONO (1725 3425);
DISPLAY INVISIBLE (1725 3425);
FORCEPROP 2 LAST CDS_LIB mstr_discrete
J 0
(1675 3250);
PAINT ORANGE (1675 3250);
DISPLAY INVISIBLE (1675 3250);
FORCEPROP 2 LAST ROOM VDDQ_ABC_PWR_VR
J 0
(1725 3425);
DISPLAY 1.361702 (1725 3425);
PAINT ORANGE (1725 3425);
DISPLAY INVISIBLE (1725 3425);
FORCEPROP 2 LAST CDS_LOCATION R3T13
J 0
(1720 3375);
DISPLAY 0.617021 (1720 3375);
PAINT AQUA (1720 3375);
DISPLAY INVISIBLE (1720 3375);
FORCEPROP 2 LAST SEC 1
J 0
(1725 3500);
DISPLAY 0.680851 (1725 3500);
PAINT MONO (1725 3500);
DISPLAY INVISIBLE (1725 3500);
FORCEPROP 2 LAST SEC_TYPE 0402
J 0
(1725 3500);
DISPLAY 1.021277 (1725 3500);
PAINT ORANGE (1725 3500);
DISPLAY INVISIBLE (1725 3500);
FORCEADD CAP_A..1
(1975 2900);
FORCEPROP 1 LAST PART_NUMBER A36096-030
J 0
(2025 2750);
DISPLAY 0.617021 (2025 2750);
PAINT BLUE (2025 2750);
FORCEPROP 1 LAST PACK_TYPE 0402V
J 0
(2025 2700);
DISPLAY 0.617021 (2025 2700);
PAINT SKYBLUE (2025 2700);
FORCEPROP 1 LASTPIN (1975 3000) $PN 1
J 0
(1985 2980);
DISPLAY 0.617021 (1985 2980);
PAINT ORANGE (1985 2980);
FORCEPROP 1 LAST VOLTAGE 16V
J 0
(2025 2900);
DISPLAY 0.617021 (2025 2900);
PAINT SKYBLUE (2025 2900);
FORCEPROP 1 LAST TOLERANCE 10%
J 0
(2025 2850);
DISPLAY 0.617021 (2025 2850);
PAINT SKYBLUE (2025 2850);
FORCEPROP 1 LAST MATERIAL X7R
J 0
(2025 2800);
DISPLAY 0.617021 (2025 2800);
PAINT SKYBLUE (2025 2800);
FORCEPROP 1 LAST VALUE 0.1UF
J 0
(2025 2950);
DISPLAY 0.617021 (2025 2950);
PAINT SKYBLUE (2025 2950);
FORCEPROP 1 LAST LOCATION C7F17
J 0
(2025 3000);
DISPLAY 0.617021 (2025 3000);
PAINT AQUA (2025 3000);
FORCEPROP 1 LASTPIN (1975 2800) $PN 2
J 0
(1985 2780);
DISPLAY 0.617021 (1985 2780);
PAINT ORANGE (1985 2780);
FORCEPROP 1 LAST PATH I34
J 0
(2025 3050);
DISPLAY 0.978723 (2025 3050);
PAINT WHITE (2025 3050);
DISPLAY INVISIBLE (2025 3050);
FORCEPROP 2 LAST CDS_LOCATION C7F17
J 0
(2025 3000);
DISPLAY 0.617021 (2025 3000);
PAINT AQUA (2025 3000);
DISPLAY INVISIBLE (2025 3000);
FORCEPROP 2 LAST CDS_LIB dev_discrete
J 0
(1975 2900);
PAINT ORANGE (1975 2900);
DISPLAY INVISIBLE (1975 2900);
FORCEPROP 2 LAST ROOM VDDQ_ABC_PWR_VR
J 0
(2025 3050);
DISPLAY 1.361702 (2025 3050);
PAINT ORANGE (2025 3050);
DISPLAY INVISIBLE (2025 3050);
FORCEPROP 2 LAST CDS_SEC 1
J 0
(2025 3050);
PAINT ORANGE (2025 3050);
DISPLAY INVISIBLE (2025 3050);
FORCEPROP 2 LAST SEC_TYPE 0402V
J 0
(2025 3125);
DISPLAY 1.021277 (2025 3125);
PAINT ORANGE (2025 3125);
DISPLAY INVISIBLE (2025 3125);
FORCEPROP 2 LAST SEC 1
J 0
(2025 3125);
DISPLAY 0.680851 (2025 3125);
PAINT MONO (2025 3125);
DISPLAY INVISIBLE (2025 3125);
FORCEADD CAP_A..1
(2375 2900);
FORCEPROP 1 LAST VOLTAGE 6.3V
J 0
(2425 2900);
DISPLAY 0.617021 (2425 2900);
PAINT SKYBLUE (2425 2900);
FORCEPROP 1 LAST TOLERANCE 10%
J 0
(2425 2850);
DISPLAY 0.617021 (2425 2850);
PAINT SKYBLUE (2425 2850);
FORCEPROP 1 LAST MATERIAL X6S
J 0
(2425 2800);
DISPLAY 0.617021 (2425 2800);
PAINT SKYBLUE (2425 2800);
FORCEPROP 1 LAST LOCATION C7F18
J 0
(2425 3000);
DISPLAY 0.617021 (2425 3000);
PAINT AQUA (2425 3000);
FORCEPROP 1 LASTPIN (2375 3000) $PN 1
J 0
(2385 2980);
DISPLAY 0.787234 (2385 2980);
PAINT ORANGE (2385 2980);
FORCEPROP 1 LASTPIN (2375 2800) $PN 2
J 0
(2385 2780);
DISPLAY 0.787234 (2385 2780);
PAINT ORANGE (2385 2780);
FORCEPROP 1 LAST VALUE 1.0UF
J 0
(2425 2950);
DISPLAY 0.617021 (2425 2950);
PAINT SKYBLUE (2425 2950);
FORCEPROP 1 LAST PACK_TYPE 0402V
J 0
(2425 2700);
DISPLAY 0.617021 (2425 2700);
PAINT SKYBLUE (2425 2700);
FORCEPROP 1 LAST PART_NUMBER D97712-004
J 0
(2425 2750);
DISPLAY 0.617021 (2425 2750);
PAINT BLUE (2425 2750);
FORCEPROP 1 LAST PATH I35
J 0
(2425 3050);
DISPLAY 0.978723 (2425 3050);
PAINT WHITE (2425 3050);
DISPLAY INVISIBLE (2425 3050);
FORCEPROP 0 LAST CDS_SEC 1
J 0
(2425 3050);
PAINT MONO (2425 3050);
DISPLAY INVISIBLE (2425 3050);
FORCEPROP 2 LAST CDS_LIB dev_discrete
J 0
(2375 2900);
PAINT ORANGE (2375 2900);
DISPLAY INVISIBLE (2375 2900);
FORCEPROP 2 LAST CDS_LOCATION C7F18
J 0
(2425 3000);
DISPLAY 0.617021 (2425 3000);
PAINT AQUA (2425 3000);
DISPLAY INVISIBLE (2425 3000);
FORCEPROP 2 LAST ROOM VDDQ_ABC_PWR_VR
J 0
(2425 3050);
DISPLAY 1.361702 (2425 3050);
PAINT ORANGE (2425 3050);
DISPLAY INVISIBLE (2425 3050);
FORCEPROP 2 LAST SEC 1
J 0
(2425 3100);
DISPLAY 0.680851 (2425 3100);
PAINT MONO (2425 3100);
DISPLAY INVISIBLE (2425 3100);
FORCEPROP 2 LAST SEC_TYPE 0402V
J 0
(2425 3100);
DISPLAY 1.021277 (2425 3100);
PAINT ORANGE (2425 3100);
DISPLAY INVISIBLE (2425 3100);
FORCEADD GND..1
(2850 625);
FORCEPROP 3 LASTPIN (2850 675) SIG_NAME GND\g
J 0
(2860 685);
DISPLAY 0.659574 (2860 685);
PAINT MONO (2860 685);
DISPLAY INVISIBLE (2860 685);
FORCEPROP 1 LAST HDL_POWER GND
J 0
(2850 775);
DISPLAY 1.170213 (2850 775);
PAINT GREEN (2850 775);
DISPLAY INVISIBLE (2850 775);
FORCEPROP 1 LAST BODY_TYPE PLUMBING
J 0
(2805 582);
DISPLAY 0.340426 (2805 582);
PAINT GREEN (2805 582);
DISPLAY INVISIBLE (2805 582);
FORCEPROP 1 LAST PATH I36
J 0
(2925 625);
DISPLAY 0.872340 (2925 625);
PAINT AQUA (2925 625);
DISPLAY INVISIBLE (2925 625);
FORCEPROP 2 LAST ROOM VDDQ_ABC_PWR_VR
J 0
(2275 700);
DISPLAY 1.361702 (2275 700);
PAINT ORANGE (2275 700);
DISPLAY INVISIBLE (2275 700);
FORCEPROP 2 LAST CDS_LIB mstr_symbols
J 0
(2850 625);
PAINT ORANGE (2850 625);
DISPLAY INVISIBLE (2850 625);
FORCEPROP 1 LAST SIZE 1B
J 0
(2925 575);
DISPLAY 1.170213 (2925 575);
PAINT AQUA (2925 575);
DISPLAY INVISIBLE (2925 575);
FORCEPROP 1 LAST VOLTAGE 0
J 0
(2850 625);
PAINT SKYBLUE (2850 625);
DISPLAY INVISIBLE (2850 625);
FORCEADD GND..1
(3150 0);
FORCEPROP 3 LASTPIN (3150 50) SIG_NAME GND\g
J 0
(3160 60);
DISPLAY 0.659574 (3160 60);
PAINT MONO (3160 60);
DISPLAY INVISIBLE (3160 60);
FORCEPROP 1 LAST HDL_POWER GND
J 0
(3150 150);
DISPLAY 1.170213 (3150 150);
PAINT GREEN (3150 150);
DISPLAY INVISIBLE (3150 150);
FORCEPROP 1 LAST BODY_TYPE PLUMBING
J 0
(3105 -43);
DISPLAY 0.340426 (3105 -43);
PAINT GREEN (3105 -43);
DISPLAY INVISIBLE (3105 -43);
FORCEPROP 1 LAST PATH I37
J 0
(3225 0);
DISPLAY 0.872340 (3225 0);
PAINT AQUA (3225 0);
DISPLAY INVISIBLE (3225 0);
FORCEPROP 2 LAST ROOM VDDQ_ABC_PWR_VR
J 0
(2575 75);
DISPLAY 1.361702 (2575 75);
PAINT ORANGE (2575 75);
DISPLAY INVISIBLE (2575 75);
FORCEPROP 1 LAST SIZE 1B
J 0
(3225 -50);
DISPLAY 1.170213 (3225 -50);
PAINT AQUA (3225 -50);
DISPLAY INVISIBLE (3225 -50);
FORCEPROP 1 LAST VOLTAGE 0
J 0
(3150 0);
PAINT SKYBLUE (3150 0);
DISPLAY INVISIBLE (3150 0);
FORCEPROP 2 LAST CDS_LIB mstr_symbols
J 0
(3150 0);
PAINT ORANGE (3150 0);
DISPLAY INVISIBLE (3150 0);
FORCEADD CAP_A..1
(3150 200);
FORCEPROP 1 LAST MATERIAL X7R
J 0
(3200 100);
DISPLAY 0.617021 (3200 100);
PAINT SKYBLUE (3200 100);
FORCEPROP 1 LAST TOLERANCE 10%
J 0
(3200 150);
DISPLAY 0.617021 (3200 150);
PAINT SKYBLUE (3200 150);
FORCEPROP 1 LAST VOLTAGE 16V
J 0
(3200 200);
DISPLAY 0.617021 (3200 200);
PAINT SKYBLUE (3200 200);
FORCEPROP 1 LASTPIN (3150 300) $PN 1
J 0
(3160 280);
DISPLAY 0.617021 (3160 280);
PAINT ORANGE (3160 280);
FORCEPROP 1 LASTPIN (3150 100) $PN 2
J 0
(3160 80);
DISPLAY 0.617021 (3160 80);
PAINT ORANGE (3160 80);
FORCEPROP 1 LAST PACK_TYPE 0402V
J 0
(3200 0);
DISPLAY 0.617021 (3200 0);
PAINT SKYBLUE (3200 0);
FORCEPROP 1 LAST PART_NUMBER A36096-030
J 0
(3200 50);
DISPLAY 0.617021 (3200 50);
PAINT BLUE (3200 50);
FORCEPROP 1 LAST VALUE 0.1UF
J 0
(3200 250);
DISPLAY 0.617021 (3200 250);
PAINT SKYBLUE (3200 250);
FORCEPROP 1 LAST LOCATION C7F15
J 0
(3200 300);
DISPLAY 0.617021 (3200 300);
PAINT AQUA (3200 300);
FORCEPROP 1 LAST PATH I38
J 0
(3200 350);
DISPLAY 0.978723 (3200 350);
PAINT WHITE (3200 350);
DISPLAY INVISIBLE (3200 350);
FORCEPROP 2 LAST CDS_LIB dev_discrete
J 0
(3150 200);
PAINT ORANGE (3150 200);
DISPLAY INVISIBLE (3150 200);
FORCEPROP 2 LAST ROOM VDDQ_ABC_PWR_VR
J 0
(3200 350);
DISPLAY 1.361702 (3200 350);
PAINT ORANGE (3200 350);
DISPLAY INVISIBLE (3200 350);
FORCEPROP 2 LAST CDS_LOCATION C7F15
J 0
(3200 300);
DISPLAY 0.617021 (3200 300);
PAINT AQUA (3200 300);
DISPLAY INVISIBLE (3200 300);
FORCEPROP 2 LAST CDS_SEC 1
J 0
(3200 350);
PAINT ORANGE (3200 350);
DISPLAY INVISIBLE (3200 350);
FORCEPROP 2 LAST SEC_TYPE 0402V
J 0
(3200 425);
DISPLAY 1.021277 (3200 425);
PAINT ORANGE (3200 425);
DISPLAY INVISIBLE (3200 425);
FORCEPROP 2 LAST SEC 1
J 0
(3200 425);
DISPLAY 0.680851 (3200 425);
PAINT MONO (3200 425);
DISPLAY INVISIBLE (3200 425);
FORCEADD GND..1
(3550 -75);
FORCEPROP 3 LASTPIN (3550 -25) SIG_NAME GND\g
J 0
(3560 -15);
DISPLAY 0.659574 (3560 -15);
PAINT MONO (3560 -15);
DISPLAY INVISIBLE (3560 -15);
FORCEPROP 1 LAST HDL_POWER GND
J 0
(3550 75);
DISPLAY 1.170213 (3550 75);
PAINT GREEN (3550 75);
DISPLAY INVISIBLE (3550 75);
FORCEPROP 1 LAST BODY_TYPE PLUMBING
J 0
(3505 -118);
DISPLAY 0.340426 (3505 -118);
PAINT GREEN (3505 -118);
DISPLAY INVISIBLE (3505 -118);
FORCEPROP 1 LAST PATH I39
J 0
(3625 -75);
DISPLAY 0.872340 (3625 -75);
PAINT AQUA (3625 -75);
DISPLAY INVISIBLE (3625 -75);
FORCEPROP 2 LAST ROOM VDDQ_ABC_PWR_VR
J 0
(2975 0);
DISPLAY 1.361702 (2975 0);
PAINT ORANGE (2975 0);
DISPLAY INVISIBLE (2975 0);
FORCEPROP 1 LAST VOLTAGE 0
J 0
(3550 -75);
PAINT SKYBLUE (3550 -75);
DISPLAY INVISIBLE (3550 -75);
FORCEPROP 2 LAST CDS_LIB mstr_symbols
J 0
(3550 -75);
PAINT ORANGE (3550 -75);
DISPLAY INVISIBLE (3550 -75);
FORCEPROP 1 LAST SIZE 1B
J 0
(3625 -125);
DISPLAY 1.170213 (3625 -125);
PAINT AQUA (3625 -125);
DISPLAY INVISIBLE (3625 -125);
FORCEADD OFFPAGE..1
(-1400 1700);
FORCEPROP 2 LAST $XR0 197 
J 0
(-1652 1700);
DISPLAY 0.638298 (-1652 1700);
PAINT MONO (-1652 1700);
FORCEPROP 1 LAST COMMENT_BODY TRUE
J 0
(-1275 1600);
DISPLAY 1.170213 (-1275 1600);
PAINT GREEN (-1275 1600);
DISPLAY INVISIBLE (-1275 1600);
FORCEPROP 1 LAST OFFPAGE TRUE
J 0
(-1075 1575);
DISPLAY 1.170213 (-1075 1575);
PAINT GREEN (-1075 1575);
DISPLAY INVISIBLE (-1075 1575);
FORCEPROP 2 LAST PATH I4
J 0
(-1650 1750);
DISPLAY 1.021277 (-1650 1750);
PAINT ORANGE (-1650 1750);
DISPLAY INVISIBLE (-1650 1750);
FORCEPROP 2 LAST ROOM VDDQ_ABC_PWR_VR
J 0
(-1950 1775);
DISPLAY 1.361702 (-1950 1775);
PAINT ORANGE (-1950 1775);
DISPLAY INVISIBLE (-1950 1775);
FORCEPROP 2 LAST CDS_LIB mstr_standard
J 0
(-1400 1700);
PAINT ORANGE (-1400 1700);
DISPLAY INVISIBLE (-1400 1700);
FORCEADD CAP_A..1
(3550 200);
FORCEPROP 1 LASTPIN (3550 100) $PN 2
J 0
(3560 80);
DISPLAY 0.617021 (3560 80);
PAINT ORANGE (3560 80);
FORCEPROP 1 LASTPIN (3550 300) $PN 1
J 0
(3560 280);
DISPLAY 0.617021 (3560 280);
PAINT ORANGE (3560 280);
FORCEPROP 1 LAST MATERIAL X6S
J 0
(3600 100);
DISPLAY 0.617021 (3600 100);
PAINT SKYBLUE (3600 100);
FORCEPROP 1 LAST TOLERANCE 10%
J 0
(3600 150);
DISPLAY 0.617021 (3600 150);
PAINT SKYBLUE (3600 150);
FORCEPROP 1 LAST PART_NUMBER D97712-004
J 0
(3600 50);
DISPLAY 0.617021 (3600 50);
PAINT BLUE (3600 50);
FORCEPROP 1 LAST LOCATION C7F16
J 0
(3600 300);
DISPLAY 0.617021 (3600 300);
PAINT AQUA (3600 300);
FORCEPROP 1 LAST PACK_TYPE 0402V
J 0
(3600 0);
DISPLAY 0.617021 (3600 0);
PAINT SKYBLUE (3600 0);
FORCEPROP 1 LAST VALUE 1.0UF
J 0
(3600 250);
DISPLAY 0.617021 (3600 250);
PAINT SKYBLUE (3600 250);
FORCEPROP 1 LAST VOLTAGE 6.3V
J 0
(3600 200);
DISPLAY 0.617021 (3600 200);
PAINT SKYBLUE (3600 200);
FORCEPROP 1 LAST PATH I40
J 0
(3600 350);
DISPLAY 0.978723 (3600 350);
PAINT WHITE (3600 350);
DISPLAY INVISIBLE (3600 350);
FORCEPROP 2 LAST CDS_LIB dev_discrete
J 0
(3550 200);
PAINT ORANGE (3550 200);
DISPLAY INVISIBLE (3550 200);
FORCEPROP 2 LAST CDS_LOCATION C7F16
J 0
(3600 300);
DISPLAY 0.617021 (3600 300);
PAINT AQUA (3600 300);
DISPLAY INVISIBLE (3600 300);
FORCEPROP 2 LAST CDS_SEC 1
J 0
(3600 350);
PAINT ORANGE (3600 350);
DISPLAY INVISIBLE (3600 350);
FORCEPROP 2 LAST SEC_TYPE 0402V
J 0
(3600 400);
DISPLAY 1.021277 (3600 400);
PAINT ORANGE (3600 400);
DISPLAY INVISIBLE (3600 400);
FORCEPROP 2 LAST SEC 1
J 0
(3600 400);
DISPLAY 0.680851 (3600 400);
PAINT MONO (3600 400);
DISPLAY INVISIBLE (3600 400);
FORCEPROP 2 LAST ROOM VDDQ_ABC_PWR_VR
J 0
(3600 350);
DISPLAY 1.361702 (3600 350);
PAINT ORANGE (3600 350);
DISPLAY INVISIBLE (3600 350);
FORCEADD RES..1
(3625 1500);
FORCEPROP 1 LAST TOLERANCE 5%
J 0
(3575 1400);
DISPLAY 0.617021 (3575 1400);
PAINT SKYBLUE (3575 1400);
FORCEPROP 1 LASTPIN (3525 1500) $PN 1
J 0
(3537 1512);
DISPLAY 0.617021 (3537 1512);
PAINT ORANGE (3537 1512);
FORCEPROP 1 LASTPIN (3725 1500) $PN 2
J 0
(3687 1512);
DISPLAY 0.617021 (3687 1512);
PAINT ORANGE (3687 1512);
FORCEPROP 1 LAST LOCATION R7G2
J 0
(3575 1550);
DISPLAY 0.617021 (3575 1550);
PAINT AQUA (3575 1550);
FORCEPROP 1 LAST VALUE 0.0
J 2
(3525 1400);
DISPLAY 0.617021 (3525 1400);
PAINT SKYBLUE (3525 1400);
FORCEPROP 1 LAST PART_NUMBER G21497-005
J 0
(3475 1450);
DISPLAY 0.617021 (3475 1450);
PAINT BLUE (3475 1450);
FORCEPROP 1 LAST PACK_TYPE 0402
J 0
(3700 1400);
DISPLAY 0.617021 (3700 1400);
PAINT SKYBLUE (3700 1400);
FORCEPROP 1 LAST WATTAGE 1/16W
J 2
(3600 1350);
DISPLAY 0.617021 (3600 1350);
PAINT SKYBLUE (3600 1350);
FORCEPROP 1 LAST MATERIAL CHIP
J 0
(3625 1350);
DISPLAY 0.617021 (3625 1350);
PAINT SKYBLUE (3625 1350);
FORCEPROP 1 LAST PATH I41
J 0
(3575 1650);
DISPLAY 0.978723 (3575 1650);
PAINT WHITE (3575 1650);
DISPLAY INVISIBLE (3575 1650);
FORCEPROP 0 LAST CDS_SEC 1
J 0
(3575 1600);
PAINT MONO (3575 1600);
DISPLAY INVISIBLE (3575 1600);
FORCEPROP 2 LAST SEC_TYPE 0402
J 0
(3575 1700);
DISPLAY 1.021277 (3575 1700);
PAINT ORANGE (3575 1700);
DISPLAY INVISIBLE (3575 1700);
FORCEPROP 2 LAST SEC 1
J 0
(3575 1700);
DISPLAY 0.680851 (3575 1700);
PAINT MONO (3575 1700);
DISPLAY INVISIBLE (3575 1700);
FORCEPROP 2 LAST CDS_LOCATION R7G2
J 0
(3575 1550);
DISPLAY 0.617021 (3575 1550);
PAINT AQUA (3575 1550);
DISPLAY INVISIBLE (3575 1550);
FORCEPROP 2 LAST ROOM VDDQ_ABC_PWR_VR
J 0
(3575 1600);
DISPLAY 1.361702 (3575 1600);
PAINT ORANGE (3575 1600);
DISPLAY INVISIBLE (3575 1600);
FORCEPROP 2 LAST CDS_LIB mstr_discrete
J 0
(3625 1500);
PAINT ORANGE (3625 1500);
DISPLAY INVISIBLE (3625 1500);
FORCEADD OFFPAGE..1
R 2
(4100 375);
FORCEPROP 2 LAST $XR0 215 
J 0
(4286 375);
DISPLAY 0.638298 (4286 375);
PAINT MONO (4286 375);
FORCEPROP 1 LAST COMMENT_BODY TRUE
J 2
(3975 275);
DISPLAY 1.170213 (3975 275);
PAINT GREEN (3975 275);
DISPLAY INVISIBLE (3975 275);
FORCEPROP 1 LAST OFFPAGE TRUE
J 2
(3775 250);
DISPLAY 1.170213 (3775 250);
PAINT GREEN (3775 250);
DISPLAY INVISIBLE (3775 250);
FORCEPROP 2 LAST PATH I42
J 0
(4300 425);
DISPLAY 1.021277 (4300 425);
PAINT ORANGE (4300 425);
DISPLAY INVISIBLE (4300 425);
FORCEPROP 2 LAST CDS_LIB mstr_standard
J 2
(4100 375);
PAINT ORANGE (4100 375);
DISPLAY INVISIBLE (4100 375);
FORCEPROP 2 LAST ROOM VDDQ_ABC_PWR_VR
J 0
(3675 450);
DISPLAY 1.361702 (3675 450);
PAINT ORANGE (3675 450);
DISPLAY INVISIBLE (3675 450);
FORCEADD GND..1
(3800 775);
FORCEPROP 3 LASTPIN (3800 825) SIG_NAME GND\g
J 0
(3810 835);
DISPLAY 0.659574 (3810 835);
PAINT MONO (3810 835);
DISPLAY INVISIBLE (3810 835);
FORCEPROP 1 LAST HDL_POWER GND
J 0
(3800 925);
DISPLAY 1.170213 (3800 925);
PAINT GREEN (3800 925);
DISPLAY INVISIBLE (3800 925);
FORCEPROP 1 LAST BODY_TYPE PLUMBING
J 0
(3755 732);
DISPLAY 0.340426 (3755 732);
PAINT GREEN (3755 732);
DISPLAY INVISIBLE (3755 732);
FORCEPROP 1 LAST PATH I43
J 0
(3875 775);
DISPLAY 0.872340 (3875 775);
PAINT AQUA (3875 775);
DISPLAY INVISIBLE (3875 775);
FORCEPROP 2 LAST ROOM VDDQ_ABC_PWR_VR
J 0
(3225 850);
DISPLAY 1.361702 (3225 850);
PAINT ORANGE (3225 850);
DISPLAY INVISIBLE (3225 850);
FORCEPROP 2 LAST CDS_LIB mstr_symbols
J 0
(3800 775);
PAINT MONO (3800 775);
DISPLAY INVISIBLE (3800 775);
FORCEPROP 1 LAST SIZE 1B
J 0
(3875 725);
DISPLAY 1.170213 (3875 725);
PAINT AQUA (3875 725);
DISPLAY INVISIBLE (3875 725);
FORCEPROP 1 LAST VOLTAGE 0
J 0
(3800 775);
PAINT SKYBLUE (3800 775);
DISPLAY INVISIBLE (3800 775);
FORCEADD CAP..1
(3800 1050);
FORCEPROP 1 LAST MATERIAL X7R
J 0
(3850 950);
DISPLAY 0.617021 (3850 950);
PAINT SKYBLUE (3850 950);
FORCEPROP 1 LAST TOLERANCE 10%
J 0
(3850 1000);
DISPLAY 0.617021 (3850 1000);
PAINT SKYBLUE (3850 1000);
FORCEPROP 1 LAST PACK_TYPE 0402LF
J 0
(3850 850);
DISPLAY 0.617021 (3850 850);
PAINT SKYBLUE (3850 850);
FORCEPROP 1 LASTPIN (3800 950) $PN 2
J 0
(3810 930);
DISPLAY 0.617021 (3810 930);
PAINT ORANGE (3810 930);
FORCEPROP 1 LAST PART_NUMBER A36096-046
J 0
(3850 900);
DISPLAY 0.617021 (3850 900);
PAINT BLUE (3850 900);
FORCEPROP 1 LAST VOLTAGE 50V
J 0
(3850 1050);
DISPLAY 0.617021 (3850 1050);
PAINT SKYBLUE (3850 1050);
FORCEPROP 1 LASTPIN (3800 1150) $PN 1
J 0
(3810 1130);
DISPLAY 0.617021 (3810 1130);
PAINT ORANGE (3810 1130);
FORCEPROP 1 LAST VALUE 1000PF
J 0
(3850 1100);
DISPLAY 0.617021 (3850 1100);
PAINT SKYBLUE (3850 1100);
FORCEPROP 1 LAST LOCATION C7F14
J 0
(3850 1150);
DISPLAY 0.617021 (3850 1150);
PAINT AQUA (3850 1150);
FORCEPROP 1 LAST PATH I44
J 0
(3850 1200);
DISPLAY 0.978723 (3850 1200);
PAINT WHITE (3850 1200);
DISPLAY INVISIBLE (3850 1200);
FORCEPROP 0 LAST CDS_SEC 1
J 0
(3850 1200);
PAINT MONO (3850 1200);
DISPLAY INVISIBLE (3850 1200);
FORCEPROP 2 LAST CDS_LOCATION C7F14
J 0
(3850 1150);
DISPLAY 0.617021 (3850 1150);
PAINT AQUA (3850 1150);
DISPLAY INVISIBLE (3850 1150);
FORCEPROP 2 LAST CDS_LIB mstr_discrete
J 0
(3800 1050);
PAINT MONO (3800 1050);
DISPLAY INVISIBLE (3800 1050);
FORCEPROP 0 LAST ROOM VDDQ_ABC_PWR_VR
J 0
(3850 1250);
DISPLAY 1.021277 (3850 1250);
PAINT ORANGE (3850 1250);
DISPLAY INVISIBLE (3850 1250);
FORCEPROP 2 LAST SEC 1
J 0
(3850 1250);
DISPLAY 0.680851 (3850 1250);
PAINT MONO (3850 1250);
DISPLAY INVISIBLE (3850 1250);
FORCEPROP 2 LAST SEC_TYPE 0402LF
J 0
(3850 1250);
DISPLAY 1.021277 (3850 1250);
PAINT ORANGE (3850 1250);
DISPLAY INVISIBLE (3850 1250);
FORCEADD RES..1
(4000 1650);
FORCEPROP 1 LAST MATERIAL EMPTY
J 0
(4350 1650);
DISPLAY 0.617021 (4350 1650);
PAINT RED (4350 1650);
FORCEPROP 1 LAST WATTAGE 1/16W
J 0
(4150 1650);
DISPLAY 0.617021 (4150 1650);
PAINT SKYBLUE (4150 1650);
FORCEPROP 1 LAST LOCATION R12W26
J 0
(3500 1650);
DISPLAY 0.617021 (3500 1650);
PAINT AQUA (3500 1650);
FORCEPROP 1 LAST VALUE 0.0
J 0
(3700 1650);
DISPLAY 0.617021 (3700 1650);
PAINT SKYBLUE (3700 1650);
FORCEPROP 1 LAST TOLERANCE 5%
J 0
(3825 1650);
DISPLAY 0.617021 (3825 1650);
PAINT SKYBLUE (3825 1650);
FORCEPROP 1 LASTPIN (4100 1650) $PN 2
J 0
(4062 1662);
DISPLAY 0.617021 (4062 1662);
PAINT ORANGE (4062 1662);
FORCEPROP 1 LAST PACK_TYPE 0402
J 0
(4750 1650);
DISPLAY 0.617021 (4750 1650);
PAINT SKYBLUE (4750 1650);
FORCEPROP 1 LAST PART_NUMBER G21497-005
J 0
(4500 1650);
DISPLAY 0.617021 (4500 1650);
PAINT BLUE (4500 1650);
FORCEPROP 1 LASTPIN (3900 1650) $PN 1
J 0
(3912 1662);
DISPLAY 0.617021 (3912 1662);
PAINT ORANGE (3912 1662);
FORCEPROP 2 LAST CDS_LIB mstr_discrete
J 0
(4000 1650);
PAINT ORANGE (4000 1650);
DISPLAY INVISIBLE (4000 1650);
FORCEPROP 0 LAST SEC 1
J 0
(3950 1800);
DISPLAY 0.680851 (3950 1800);
PAINT MONO (3950 1800);
DISPLAY INVISIBLE (3950 1800);
FORCEPROP 0 LAST ROOM NV_DIMM
J 0
(3950 1850);
DISPLAY 1.021277 (3950 1850);
PAINT ORANGE (3950 1850);
DISPLAY INVISIBLE (3950 1850);
FORCEPROP 2 LAST SEC_TYPE 0402
J 0
(3950 1850);
DISPLAY 1.021277 (3950 1850);
PAINT ORANGE (3950 1850);
DISPLAY INVISIBLE (3950 1850);
FORCEPROP 0 LAST BOM_COST MEM_NV
J 0
(3950 1950);
DISPLAY 1.021277 (3950 1950);
PAINT ORANGE (3950 1950);
DISPLAY INVISIBLE (3950 1950);
FORCEPROP 2 LAST CDS_LOCATION R12W26
J 0
(3950 1700);
DISPLAY 0.617021 (3950 1700);
PAINT AQUA (3950 1700);
DISPLAY INVISIBLE (3950 1700);
FORCEPROP 0 LAST CDS_SEC 1
J 0
(4750 1700);
PAINT MONO (4750 1700);
DISPLAY INVISIBLE (4750 1700);
FORCEPROP 1 LAST PATH I45
J 0
(3950 1800);
DISPLAY 0.978723 (3950 1800);
PAINT WHITE (3950 1800);
DISPLAY INVISIBLE (3950 1800);
FORCEADD RES..1
(3475 2200);
FORCEPROP 1 LAST TOLERANCE 5%
J 0
(3275 2150);
DISPLAY 0.617021 (3275 2150);
PAINT SKYBLUE (3275 2150);
FORCEPROP 1 LASTPIN (3375 2200) $PN 1
J 0
(3387 2212);
DISPLAY 0.617021 (3387 2212);
PAINT ORANGE (3387 2212);
FORCEPROP 1 LAST MATERIAL CHIP
J 0
(3500 2150);
DISPLAY 0.617021 (3500 2150);
PAINT SKYBLUE (3500 2150);
FORCEPROP 1 LAST PART_NUMBER G21497-005
J 0
(3075 2100);
DISPLAY 0.617021 (3075 2100);
PAINT BLUE (3075 2100);
FORCEPROP 1 LAST WATTAGE 1/16W
J 0
(3350 2150);
DISPLAY 0.617021 (3350 2150);
PAINT SKYBLUE (3350 2150);
FORCEPROP 1 LAST PACK_TYPE 0402
J 0
(3300 2100);
DISPLAY 0.617021 (3300 2100);
PAINT SKYBLUE (3300 2100);
FORCEPROP 1 LASTPIN (3575 2200) $PN 2
J 0
(3537 2212);
DISPLAY 0.617021 (3537 2212);
PAINT ORANGE (3537 2212);
FORCEPROP 1 LAST LOCATION R7G4
J 0
(3075 2150);
DISPLAY 0.617021 (3075 2150);
PAINT AQUA (3075 2150);
FORCEPROP 1 LAST VALUE 0.0
J 0
(3200 2150);
DISPLAY 0.617021 (3200 2150);
PAINT SKYBLUE (3200 2150);
FORCEPROP 1 LAST PATH I49
J 0
(3425 2350);
DISPLAY 0.978723 (3425 2350);
PAINT WHITE (3425 2350);
DISPLAY INVISIBLE (3425 2350);
FORCEPROP 0 LAST CDS_SEC 1
J 0
(3500 2200);
PAINT MONO (3500 2200);
DISPLAY INVISIBLE (3500 2200);
FORCEPROP 2 LAST CDS_LIB mstr_discrete
J 0
(3475 2200);
PAINT ORANGE (3475 2200);
DISPLAY INVISIBLE (3475 2200);
FORCEPROP 2 LAST CDS_LOCATION R7G4
J 0
(3500 2250);
DISPLAY 0.617021 (3500 2250);
PAINT AQUA (3500 2250);
DISPLAY INVISIBLE (3500 2250);
FORCEPROP 2 LAST ROOM VDDQ_ABC_PWR_VR
J 0
(3425 2300);
DISPLAY 1.361702 (3425 2300);
PAINT ORANGE (3425 2300);
DISPLAY INVISIBLE (3425 2300);
FORCEPROP 2 LAST SEC 1
J 0
(3425 2425);
DISPLAY 0.680851 (3425 2425);
PAINT MONO (3425 2425);
DISPLAY INVISIBLE (3425 2425);
FORCEPROP 2 LAST SEC_TYPE 0402
J 0
(3425 2425);
DISPLAY 1.021277 (3425 2425);
PAINT ORANGE (3425 2425);
DISPLAY INVISIBLE (3425 2425);
FORCEADD OFFPAGE..1
(-1400 1600);
FORCEPROP 2 LAST $XR0 216 
J 0
(-1652 1600);
DISPLAY 0.638298 (-1652 1600);
PAINT MONO (-1652 1600);
FORCEPROP 1 LAST COMMENT_BODY TRUE
J 0
(-1275 1500);
DISPLAY 1.170213 (-1275 1500);
PAINT GREEN (-1275 1500);
DISPLAY INVISIBLE (-1275 1500);
FORCEPROP 1 LAST OFFPAGE TRUE
J 0
(-1075 1475);
DISPLAY 1.170213 (-1075 1475);
PAINT GREEN (-1075 1475);
DISPLAY INVISIBLE (-1075 1475);
FORCEPROP 2 LAST PATH I5
J 0
(-1650 1650);
DISPLAY 1.021277 (-1650 1650);
PAINT ORANGE (-1650 1650);
DISPLAY INVISIBLE (-1650 1650);
FORCEPROP 2 LAST ROOM VDDQ_ABC_PWR_VR
J 0
(-1950 1675);
DISPLAY 1.361702 (-1950 1675);
PAINT ORANGE (-1950 1675);
DISPLAY INVISIBLE (-1950 1675);
FORCEPROP 2 LAST CDS_LIB mstr_standard
J 0
(-1400 1600);
PAINT ORANGE (-1400 1600);
DISPLAY INVISIBLE (-1400 1600);
FORCEADD RES..2
(2950 2900);
FORCEPROP 1 LAST PART_NUMBER G21796-026
J 0
(2990 2775);
DISPLAY 0.617021 (2990 2775);
PAINT BLUE (2990 2775);
FORCEPROP 1 LAST LOCATION R7F27
J 0
(2995 3025);
DISPLAY 0.617021 (2995 3025);
PAINT AQUA (2995 3025);
FORCEPROP 1 LAST PACK_TYPE 0402
J 0
(2990 2725);
DISPLAY 0.617021 (2990 2725);
PAINT SKYBLUE (2990 2725);
FORCEPROP 1 LASTPIN (2950 3000) $PN 1
J 0
(2955 2962);
DISPLAY 0.617021 (2955 2962);
PAINT ORANGE (2955 2962);
FORCEPROP 1 LAST TOLERANCE 1%
J 0
(2995 2925);
DISPLAY 0.617021 (2995 2925);
PAINT SKYBLUE (2995 2925);
FORCEPROP 1 LAST VALUE 1.00K
J 0
(2995 2975);
DISPLAY 0.617021 (2995 2975);
PAINT SKYBLUE (2995 2975);
FORCEPROP 1 LASTPIN (2950 2800) $PN 2
J 0
(2955 2810);
DISPLAY 0.617021 (2955 2810);
PAINT ORANGE (2955 2810);
FORCEPROP 1 LAST MATERIAL CHIP
J 0
(2990 2825);
DISPLAY 0.617021 (2990 2825);
PAINT SKYBLUE (2990 2825);
FORCEPROP 1 LAST WATTAGE 1/16W
J 0
(2990 2875);
DISPLAY 0.617021 (2990 2875);
PAINT SKYBLUE (2990 2875);
FORCEPROP 1 LAST PATH I50
J 0
(3000 3075);
DISPLAY 0.978723 (3000 3075);
PAINT WHITE (3000 3075);
DISPLAY INVISIBLE (3000 3075);
FORCEPROP 0 LAST CDS_SEC 1
J 0
(3000 3075);
PAINT MONO (3000 3075);
DISPLAY INVISIBLE (3000 3075);
FORCEPROP 2 LAST CDS_LIB mstr_discrete
J 0
(2950 2900);
PAINT ORANGE (2950 2900);
DISPLAY INVISIBLE (2950 2900);
FORCEPROP 2 LAST CDS_LOCATION R7F27
J 0
(2995 3025);
DISPLAY 0.617021 (2995 3025);
PAINT AQUA (2995 3025);
DISPLAY INVISIBLE (2995 3025);
FORCEPROP 2 LAST SEC_TYPE 0402
J 0
(3000 3125);
DISPLAY 1.021277 (3000 3125);
PAINT ORANGE (3000 3125);
DISPLAY INVISIBLE (3000 3125);
FORCEPROP 2 LAST SEC 1
J 0
(3000 3125);
DISPLAY 0.680851 (3000 3125);
PAINT MONO (3000 3125);
DISPLAY INVISIBLE (3000 3125);
FORCEPROP 0 LAST ROOM VDDQ_ABC_PWR_VR
J 0
(3000 3125);
DISPLAY 1.021277 (3000 3125);
PAINT ORANGE (3000 3125);
DISPLAY INVISIBLE (3000 3125);
FORCEADD RES..2
(3300 2900);
FORCEPROP 1 LAST PART_NUMBER G21796-026
J 0
(3340 2775);
DISPLAY 0.617021 (3340 2775);
PAINT BLUE (3340 2775);
FORCEPROP 1 LAST LOCATION R7F22
J 0
(3345 3025);
DISPLAY 0.617021 (3345 3025);
PAINT AQUA (3345 3025);
FORCEPROP 1 LASTPIN (3300 2800) $PN 2
J 0
(3305 2810);
DISPLAY 0.617021 (3305 2810);
PAINT ORANGE (3305 2810);
FORCEPROP 1 LAST TOLERANCE 1%
J 0
(3345 2925);
DISPLAY 0.617021 (3345 2925);
PAINT SKYBLUE (3345 2925);
FORCEPROP 1 LAST VALUE 1.00K
J 0
(3345 2975);
DISPLAY 0.617021 (3345 2975);
PAINT SKYBLUE (3345 2975);
FORCEPROP 1 LASTPIN (3300 3000) $PN 1
J 0
(3305 2962);
DISPLAY 0.617021 (3305 2962);
PAINT ORANGE (3305 2962);
FORCEPROP 1 LAST MATERIAL CHIP
J 0
(3340 2825);
DISPLAY 0.617021 (3340 2825);
PAINT SKYBLUE (3340 2825);
FORCEPROP 1 LAST PACK_TYPE 0402
J 0
(3340 2725);
DISPLAY 0.617021 (3340 2725);
PAINT SKYBLUE (3340 2725);
FORCEPROP 1 LAST WATTAGE 1/16W
J 0
(3340 2875);
DISPLAY 0.617021 (3340 2875);
PAINT SKYBLUE (3340 2875);
FORCEPROP 1 LAST PATH I51
J 0
(3350 3075);
DISPLAY 0.978723 (3350 3075);
PAINT WHITE (3350 3075);
DISPLAY INVISIBLE (3350 3075);
FORCEPROP 0 LAST CDS_SEC 1
J 0
(3350 3075);
PAINT MONO (3350 3075);
DISPLAY INVISIBLE (3350 3075);
FORCEPROP 2 LAST CDS_LIB mstr_discrete
J 2
(3300 2900);
PAINT ORANGE (3300 2900);
DISPLAY INVISIBLE (3300 2900);
FORCEPROP 2 LAST CDS_LOCATION R7F22
J 0
(3345 3025);
DISPLAY 0.617021 (3345 3025);
PAINT AQUA (3345 3025);
DISPLAY INVISIBLE (3345 3025);
FORCEPROP 2 LAST SEC 1
J 0
(3350 3150);
DISPLAY 0.680851 (3350 3150);
PAINT MONO (3350 3150);
DISPLAY INVISIBLE (3350 3150);
FORCEPROP 2 LAST SEC_TYPE 0402
J 0
(3350 3150);
DISPLAY 1.021277 (3350 3150);
PAINT ORANGE (3350 3150);
DISPLAY INVISIBLE (3350 3150);
FORCEPROP 2 LAST ROOM VDDQ_ABC_PWR_VR
J 0
(3350 3075);
DISPLAY 1.361702 (3350 3075);
PAINT ORANGE (3350 3075);
DISPLAY INVISIBLE (3350 3075);
FORCEADD P3V3_STBY..1
(3500 3575);
FORCEPROP 3 LASTPIN (3500 3525) SIG_NAME P3V3_STBY\g
J 0
(3510 3535);
DISPLAY 0.659574 (3510 3535);
PAINT MONO (3510 3535);
DISPLAY INVISIBLE (3510 3535);
FORCEPROP 1 LAST HDL_POWER P3V3_STBY
J 0
(3200 3450);
DISPLAY 0.872340 (3200 3450);
PAINT ORANGE (3200 3450);
DISPLAY INVISIBLE (3200 3450);
FORCEPROP 1 LAST BODY_TYPE PLUMBING
J 0
(3455 3532);
DISPLAY 0.340426 (3455 3532);
PAINT GREEN (3455 3532);
DISPLAY INVISIBLE (3455 3532);
FORCEPROP 1 LAST PATH I52
J 0
(3545 3577);
DISPLAY 0.340426 (3545 3577);
PAINT GREEN (3545 3577);
DISPLAY INVISIBLE (3545 3577);
FORCEPROP 1 LAST VOLTAGE 3.3V
J 0
(3455 3532);
DISPLAY 0.340426 (3455 3532);
PAINT SKYBLUE (3455 3532);
DISPLAY INVISIBLE (3455 3532);
FORCEPROP 1 LAST SIZE 1B
J 0
(3545 3597);
DISPLAY 0.340426 (3545 3597);
PAINT GREEN (3545 3597);
DISPLAY INVISIBLE (3545 3597);
FORCEPROP 2 LAST CDS_LIB mstr_symbols
J 0
(3500 3575);
PAINT ORANGE (3500 3575);
DISPLAY INVISIBLE (3500 3575);
FORCEADD RES..1
(3975 2250);
FORCEPROP 1 LAST LOCATION R7F23
J 0
(3800 2300);
DISPLAY 0.617021 (3800 2300);
PAINT AQUA (3800 2300);
FORCEPROP 1 LASTPIN (3875 2250) $PN 1
J 0
(3887 2262);
DISPLAY 0.787234 (3887 2262);
PAINT ORANGE (3887 2262);
FORCEPROP 1 LAST PART_NUMBER G21796-074
J 0
(3800 2200);
DISPLAY 0.617021 (3800 2200);
PAINT BLUE (3800 2200);
FORCEPROP 1 LAST WATTAGE 1/16W
J 0
(4100 2300);
DISPLAY 0.617021 (4100 2300);
PAINT SKYBLUE (4100 2300);
FORCEPROP 1 LASTPIN (4075 2250) $PN 2
J 0
(4037 2262);
DISPLAY 0.787234 (4037 2262);
PAINT ORANGE (4037 2262);
FORCEPROP 1 LAST TOLERANCE 1%
J 0
(4025 2300);
DISPLAY 0.617021 (4025 2300);
PAINT SKYBLUE (4025 2300);
FORCEPROP 1 LAST MATERIAL CHIP
J 0
(4225 2300);
DISPLAY 0.617021 (4225 2300);
PAINT SKYBLUE (4225 2300);
FORCEPROP 1 LAST VALUE 33.2
J 0
(3925 2300);
DISPLAY 0.617021 (3925 2300);
PAINT SKYBLUE (3925 2300);
FORCEPROP 1 LAST PACK_TYPE 0402
J 0
(4100 2200);
DISPLAY 0.617021 (4100 2200);
PAINT SKYBLUE (4100 2200);
FORCEPROP 1 LAST PATH I53
J 0
(3925 2400);
DISPLAY 0.978723 (3925 2400);
PAINT WHITE (3925 2400);
DISPLAY INVISIBLE (3925 2400);
FORCEPROP 0 LAST CDS_SEC 1
J 0
(4225 2350);
PAINT MONO (4225 2350);
DISPLAY INVISIBLE (4225 2350);
FORCEPROP 2 LAST CDS_LIB mstr_discrete
J 0
(3975 2250);
PAINT MONO (3975 2250);
DISPLAY INVISIBLE (3975 2250);
FORCEPROP 2 LAST CDS_LOCATION R7F23
J 0
(3925 2300);
DISPLAY 0.617021 (3925 2300);
PAINT AQUA (3925 2300);
DISPLAY INVISIBLE (3925 2300);
FORCEPROP 2 LAST SEC 1
J 0
(3925 2450);
PAINT MONO (3925 2450);
DISPLAY INVISIBLE (3925 2450);
FORCEPROP 2 LAST SEC_TYPE 0402
J 0
(3925 2450);
DISPLAY 1.021277 (3925 2450);
PAINT ORANGE (3925 2450);
DISPLAY INVISIBLE (3925 2450);
FORCEADD RES..1
(4000 2050);
FORCEPROP 1 LAST LOCATION R12W27
J 0
(3750 2150);
DISPLAY 0.617021 (3750 2150);
PAINT AQUA (3750 2150);
FORCEPROP 1 LAST PART_NUMBER G21497-005
J 0
(3750 2100);
DISPLAY 0.617021 (3750 2100);
PAINT BLUE (3750 2100);
FORCEPROP 1 LAST TOLERANCE 5%
J 0
(4050 2150);
DISPLAY 0.617021 (4050 2150);
PAINT SKYBLUE (4050 2150);
FORCEPROP 1 LAST VALUE 0.0
J 0
(3950 2150);
DISPLAY 0.617021 (3950 2150);
PAINT SKYBLUE (3950 2150);
FORCEPROP 1 LASTPIN (3900 2050) $PN 1
J 0
(3912 2062);
DISPLAY 0.617021 (3912 2062);
PAINT ORANGE (3912 2062);
FORCEPROP 1 LASTPIN (4100 2050) $PN 2
J 0
(4062 2062);
DISPLAY 0.617021 (4062 2062);
PAINT ORANGE (4062 2062);
FORCEPROP 1 LAST PACK_TYPE 0402
J 0
(4000 2100);
DISPLAY 0.617021 (4000 2100);
PAINT SKYBLUE (4000 2100);
FORCEPROP 1 LAST WATTAGE 1/16W
J 0
(4150 2150);
DISPLAY 0.617021 (4150 2150);
PAINT SKYBLUE (4150 2150);
FORCEPROP 1 LAST MATERIAL EMPTY
J 0
(4300 2150);
DISPLAY 0.617021 (4300 2150);
PAINT RED (4300 2150);
FORCEPROP 1 LAST PATH I54
J 0
(3950 2200);
DISPLAY 0.978723 (3950 2200);
PAINT WHITE (3950 2200);
DISPLAY INVISIBLE (3950 2200);
FORCEPROP 0 LAST CDS_SEC 1
J 0
(4300 2200);
PAINT MONO (4300 2200);
DISPLAY INVISIBLE (4300 2200);
FORCEPROP 2 LAST CDS_LOCATION R12W27
J 0
(3950 2100);
DISPLAY 0.617021 (3950 2100);
PAINT AQUA (3950 2100);
DISPLAY INVISIBLE (3950 2100);
FORCEPROP 0 LAST BOM_COST MEM_NV
J 0
(3950 2350);
DISPLAY 1.021277 (3950 2350);
PAINT ORANGE (3950 2350);
DISPLAY INVISIBLE (3950 2350);
FORCEPROP 2 LAST SEC_TYPE 0402
J 0
(3950 2250);
DISPLAY 1.021277 (3950 2250);
PAINT ORANGE (3950 2250);
DISPLAY INVISIBLE (3950 2250);
FORCEPROP 0 LAST ROOM NV_DIMM
J 0
(3950 2250);
DISPLAY 1.021277 (3950 2250);
PAINT ORANGE (3950 2250);
DISPLAY INVISIBLE (3950 2250);
FORCEPROP 0 LAST SEC 1
J 0
(3950 2200);
DISPLAY 0.680851 (3950 2200);
PAINT MONO (3950 2200);
DISPLAY INVISIBLE (3950 2200);
FORCEPROP 2 LAST CDS_LIB mstr_discrete
J 0
(4000 2050);
PAINT ORANGE (4000 2050);
DISPLAY INVISIBLE (4000 2050);
FORCEADD OFFPAGE..2
(3850 2600);
FORCEPROP 2 LAST $XR0 221 
J 0
(4039 2600);
DISPLAY 0.638298 (4039 2600);
PAINT MONO (4039 2600);
FORCEPROP 1 LAST COMMENT_BODY TRUE
J 0
(3805 2505);
DISPLAY 1.170213 (3805 2505);
PAINT GREEN (3805 2505);
DISPLAY INVISIBLE (3805 2505);
FORCEPROP 1 LAST OFFPAGE TRUE
J 0
(4175 2475);
DISPLAY 1.170213 (4175 2475);
PAINT GREEN (4175 2475);
DISPLAY INVISIBLE (4175 2475);
FORCEPROP 2 LAST PATH I55
J 0
(4050 2650);
DISPLAY 1.021277 (4050 2650);
PAINT ORANGE (4050 2650);
DISPLAY INVISIBLE (4050 2650);
FORCEPROP 2 LAST CDS_LIB mstr_standard
J 0
(3850 2600);
PAINT MONO (3850 2600);
DISPLAY INVISIBLE (3850 2600);
FORCEPROP 2 LAST ROOM VDDQ_ABC_PWR_VR
J 0
(3425 2675);
DISPLAY 1.361702 (3425 2675);
PAINT ORANGE (3425 2675);
DISPLAY INVISIBLE (3425 2675);
FORCEADD RES..1
(4050 2350);
FORCEPROP 1 LAST TOLERANCE 1.0%
J 0
(4325 2425);
DISPLAY 0.617021 (4325 2425);
PAINT SKYBLUE (4325 2425);
FORCEPROP 1 LAST PACK_TYPE 0402
J 0
(4200 2425);
DISPLAY 0.617021 (4200 2425);
PAINT SKYBLUE (4200 2425);
FORCEPROP 1 LAST PART_NUMBER G21796-250
J 0
(4000 2475);
DISPLAY 0.617021 (4000 2475);
PAINT BLUE (4000 2475);
FORCEPROP 1 LAST VALUE 22.1
J 2
(3875 2425);
DISPLAY 0.617021 (3875 2425);
PAINT SKYBLUE (3875 2425);
FORCEPROP 1 LAST MATERIAL CHIP
J 0
(4050 2425);
DISPLAY 0.617021 (4050 2425);
PAINT SKYBLUE (4050 2425);
FORCEPROP 1 LASTPIN (4150 2350) $PN 2
J 0
(4137 2362);
DISPLAY 0.617021 (4137 2362);
PAINT ORANGE (4137 2362);
FORCEPROP 0 LAST POP NOPOP
J 0
(3975 2375);
DISPLAY 0.638298 (3975 2375);
PAINT RED (3975 2375);
FORCEPROP 1 LASTPIN (3950 2350) $PN 1
J 0
(3937 2362);
DISPLAY 0.617021 (3937 2362);
PAINT ORANGE (3937 2362);
FORCEPROP 1 LAST WATTAGE 1/16W
J 2
(4000 2425);
DISPLAY 0.617021 (4000 2425);
PAINT SKYBLUE (4000 2425);
FORCEPROP 1 LAST LOCATION R7F24
J 0
(3850 2475);
DISPLAY 0.617021 (3850 2475);
PAINT AQUA (3850 2475);
FORCEPROP 1 LAST PATH I56
J 0
(4000 2500);
DISPLAY 0.978723 (4000 2500);
PAINT WHITE (4000 2500);
DISPLAY INVISIBLE (4000 2500);
FORCEPROP 0 LAST CDS_SEC 1
J 0
(4000 2500);
PAINT MONO (4000 2500);
DISPLAY INVISIBLE (4000 2500);
FORCEPROP 2 LAST ROOM VDDQ_ABC_PWR_VR
J 0
(4000 2450);
DISPLAY 1.361702 (4000 2450);
PAINT ORANGE (4000 2450);
DISPLAY INVISIBLE (4000 2450);
FORCEPROP 2 LAST CDS_LOCATION R7F24
J 0
(4000 2400);
DISPLAY 0.617021 (4000 2400);
PAINT AQUA (4000 2400);
DISPLAY INVISIBLE (4000 2400);
FORCEPROP 2 LAST CDS_LIB mstr_discrete
J 0
(4050 2350);
PAINT MONO (4050 2350);
DISPLAY INVISIBLE (4050 2350);
FORCEPROP 2 LAST SEC 1
J 0
(4000 2550);
DISPLAY 0.680851 (4000 2550);
PAINT MONO (4000 2550);
DISPLAY INVISIBLE (4000 2550);
FORCEPROP 2 LAST SEC_TYPE 0402
J 0
(4000 2550);
DISPLAY 1.021277 (4000 2550);
PAINT ORANGE (4000 2550);
DISPLAY INVISIBLE (4000 2550);
FORCEADD RES..2
(4750 2650);
FORCEPROP 1 LAST LOCATION R3U2
J 0
(4795 2775);
DISPLAY 0.617021 (4795 2775);
PAINT AQUA (4795 2775);
FORCEPROP 1 LASTPIN (4750 2550) $PN 2
J 0
(4755 2560);
DISPLAY 0.617021 (4755 2560);
PAINT ORANGE (4755 2560);
FORCEPROP 1 LAST MATERIAL CHIP
J 0
(4790 2575);
DISPLAY 0.617021 (4790 2575);
PAINT SKYBLUE (4790 2575);
FORCEPROP 1 LAST WATTAGE 1/16W
J 0
(4790 2625);
DISPLAY 0.617021 (4790 2625);
PAINT SKYBLUE (4790 2625);
FORCEPROP 1 LASTPIN (4750 2750) $PN 1
J 0
(4755 2712);
DISPLAY 0.617021 (4755 2712);
PAINT ORANGE (4755 2712);
FORCEPROP 1 LAST TOLERANCE 1%
J 0
(4795 2675);
DISPLAY 0.617021 (4795 2675);
PAINT SKYBLUE (4795 2675);
FORCEPROP 1 LAST VALUE 100.0
J 0
(4795 2725);
DISPLAY 0.617021 (4795 2725);
PAINT SKYBLUE (4795 2725);
FORCEPROP 1 LAST PACK_TYPE 0402
J 0
(4790 2475);
DISPLAY 0.617021 (4790 2475);
PAINT SKYBLUE (4790 2475);
FORCEPROP 1 LAST PART_NUMBER G21796-017
J 0
(4790 2525);
DISPLAY 0.617021 (4790 2525);
PAINT BLUE (4790 2525);
FORCEPROP 1 LAST PATH I58
J 0
(4800 2825);
DISPLAY 0.978723 (4800 2825);
PAINT WHITE (4800 2825);
DISPLAY INVISIBLE (4800 2825);
FORCEPROP 0 LAST CDS_SEC 1
J 0
(4800 2825);
PAINT MONO (4800 2825);
DISPLAY INVISIBLE (4800 2825);
FORCEPROP 2 LAST CDS_LIB mstr_discrete
J 0
(4750 2650);
PAINT ORANGE (4750 2650);
DISPLAY INVISIBLE (4750 2650);
FORCEPROP 2 LAST CDS_LOCATION R3U2
J 0
(4795 2775);
DISPLAY 0.617021 (4795 2775);
PAINT AQUA (4795 2775);
DISPLAY INVISIBLE (4795 2775);
FORCEPROP 2 LAST SEC_TYPE 0402
J 0
(4800 2900);
DISPLAY 1.021277 (4800 2900);
PAINT ORANGE (4800 2900);
DISPLAY INVISIBLE (4800 2900);
FORCEPROP 2 LAST SEC 1
J 0
(4800 2900);
DISPLAY 0.680851 (4800 2900);
PAINT MONO (4800 2900);
DISPLAY INVISIBLE (4800 2900);
FORCEPROP 2 LAST ROOM VDDQ_ABC_PWR_VR
J 0
(4800 2825);
DISPLAY 1.361702 (4800 2825);
PAINT ORANGE (4800 2825);
DISPLAY INVISIBLE (4800 2825);
FORCEADD PVCCIO_CPU0..1
(4750 2850);
FORCEPROP 3 LASTPIN (4750 2800) SIG_NAME PVCCIO_CPU0\g
J 0
(4760 2810);
DISPLAY 0.659574 (4760 2810);
PAINT MONO (4760 2810);
DISPLAY INVISIBLE (4760 2810);
FORCEPROP 1 LAST HDL_POWER PVCCIO_CPU0
J 1
(4750 2900);
DISPLAY 0.872340 (4750 2900);
PAINT GREEN (4750 2900);
DISPLAY INVISIBLE (4750 2900);
FORCEPROP 1 LAST BODY_TYPE PLUMBING
J 0
(4705 2807);
DISPLAY 0.340426 (4705 2807);
PAINT GREEN (4705 2807);
DISPLAY INVISIBLE (4705 2807);
FORCEPROP 1 LAST PATH I59
J 0
(4800 2875);
DISPLAY 0.872340 (4800 2875);
PAINT AQUA (4800 2875);
DISPLAY INVISIBLE (4800 2875);
FORCEPROP 1 LAST VOLTAGE 1.1V
J 0
(4705 2807);
DISPLAY 0.340426 (4705 2807);
PAINT SKYBLUE (4705 2807);
DISPLAY INVISIBLE (4705 2807);
FORCEPROP 2 LAST CDS_LIB mstr_symbols
J 0
(4750 2850);
PAINT ORANGE (4750 2850);
DISPLAY INVISIBLE (4750 2850);
FORCEADD OFFPAGE..1
(-1400 1750);
FORCEPROP 2 LAST $XR0 197 
J 0
(-1652 1750);
DISPLAY 0.638298 (-1652 1750);
PAINT MONO (-1652 1750);
FORCEPROP 1 LAST COMMENT_BODY TRUE
J 0
(-1275 1650);
DISPLAY 1.170213 (-1275 1650);
PAINT GREEN (-1275 1650);
DISPLAY INVISIBLE (-1275 1650);
FORCEPROP 1 LAST OFFPAGE TRUE
J 0
(-1075 1625);
DISPLAY 1.170213 (-1075 1625);
PAINT GREEN (-1075 1625);
DISPLAY INVISIBLE (-1075 1625);
FORCEPROP 2 LAST PATH I6
J 0
(-1650 1800);
DISPLAY 1.021277 (-1650 1800);
PAINT ORANGE (-1650 1800);
DISPLAY INVISIBLE (-1650 1800);
FORCEPROP 2 LAST ROOM VDDQ_ABC_PWR_VR
J 0
(-1950 1825);
DISPLAY 1.361702 (-1950 1825);
PAINT ORANGE (-1950 1825);
DISPLAY INVISIBLE (-1950 1825);
FORCEPROP 2 LAST CDS_LIB mstr_standard
J 0
(-1400 1750);
PAINT ORANGE (-1400 1750);
DISPLAY INVISIBLE (-1400 1750);
FORCEADD OFFPAGE..2
(5000 1250);
FORCEPROP 2 LAST $XR0 216 
J 0
(5189 1250);
DISPLAY 0.638298 (5189 1250);
PAINT MONO (5189 1250);
FORCEPROP 1 LAST COMMENT_BODY TRUE
J 0
(4955 1155);
DISPLAY 1.170213 (4955 1155);
PAINT GREEN (4955 1155);
DISPLAY INVISIBLE (4955 1155);
FORCEPROP 1 LAST OFFPAGE TRUE
J 0
(5325 1125);
DISPLAY 1.170213 (5325 1125);
PAINT GREEN (5325 1125);
DISPLAY INVISIBLE (5325 1125);
FORCEPROP 2 LAST PATH I60
J 0
(5200 1300);
DISPLAY 1.021277 (5200 1300);
PAINT ORANGE (5200 1300);
DISPLAY INVISIBLE (5200 1300);
FORCEPROP 2 LAST CDS_LIB mstr_standard
J 0
(5000 1250);
PAINT ORANGE (5000 1250);
DISPLAY INVISIBLE (5000 1250);
FORCEPROP 2 LAST ROOM VDDQ_ABC_PWR_VR
J 0
(4575 1325);
DISPLAY 1.361702 (4575 1325);
PAINT ORANGE (4575 1325);
DISPLAY INVISIBLE (4575 1325);
FORCEADD OFFPAGE..2
(5000 1300);
FORCEPROP 2 LAST $XR0 216 
J 0
(5189 1300);
DISPLAY 0.638298 (5189 1300);
PAINT MONO (5189 1300);
FORCEPROP 1 LAST COMMENT_BODY TRUE
J 0
(4955 1205);
DISPLAY 1.170213 (4955 1205);
PAINT GREEN (4955 1205);
DISPLAY INVISIBLE (4955 1205);
FORCEPROP 1 LAST OFFPAGE TRUE
J 0
(5325 1175);
DISPLAY 1.170213 (5325 1175);
PAINT GREEN (5325 1175);
DISPLAY INVISIBLE (5325 1175);
FORCEPROP 2 LAST PATH I61
J 0
(5200 1350);
DISPLAY 1.021277 (5200 1350);
PAINT ORANGE (5200 1350);
DISPLAY INVISIBLE (5200 1350);
FORCEPROP 2 LAST CDS_LIB mstr_standard
J 0
(5000 1300);
PAINT ORANGE (5000 1300);
DISPLAY INVISIBLE (5000 1300);
FORCEPROP 2 LAST ROOM VDDQ_ABC_PWR_VR
J 0
(4575 1375);
DISPLAY 1.361702 (4575 1375);
PAINT ORANGE (4575 1375);
DISPLAY INVISIBLE (4575 1375);
FORCEADD OFFPAGE..3
(5000 1500);
FORCEPROP 2 LAST $XR2 218 
J 0
(5424 1500);
DISPLAY 0.638298 (5424 1500);
PAINT MONO (5424 1500);
FORCEPROP 2 LAST $XR1 194 
J 0
(5304 1500);
DISPLAY 0.638298 (5304 1500);
PAINT MONO (5304 1500);
FORCEPROP 2 LAST $XR0 21 
J 0
(5214 1500);
DISPLAY 0.638298 (5214 1500);
PAINT MONO (5214 1500);
FORCEPROP 1 LAST COMMENT_BODY TRUE
J 0
(4950 1400);
DISPLAY 1.170213 (4950 1400);
PAINT GREEN (4950 1400);
DISPLAY INVISIBLE (4950 1400);
FORCEPROP 1 LAST OFFPAGE TRUE
J 0
(5325 1375);
DISPLAY 1.170213 (5325 1375);
PAINT GREEN (5325 1375);
DISPLAY INVISIBLE (5325 1375);
FORCEPROP 2 LAST PATH I62
J 0
(5425 1550);
DISPLAY 1.021277 (5425 1550);
PAINT ORANGE (5425 1550);
DISPLAY INVISIBLE (5425 1550);
FORCEPROP 2 LAST CDS_LIB mstr_standard
J 0
(5000 1500);
PAINT ORANGE (5000 1500);
DISPLAY INVISIBLE (5000 1500);
FORCEPROP 2 LAST ROOM VDDQ_ABC_PWR_VR
J 0
(4600 1575);
DISPLAY 1.361702 (4600 1575);
PAINT ORANGE (4600 1575);
DISPLAY INVISIBLE (4600 1575);
FORCEADD OFFPAGE..2
(5000 1550);
FORCEPROP 2 LAST $XR0 215 
J 0
(5189 1550);
DISPLAY 0.638298 (5189 1550);
PAINT MONO (5189 1550);
FORCEPROP 1 LAST COMMENT_BODY TRUE
J 0
(4955 1455);
DISPLAY 1.170213 (4955 1455);
PAINT GREEN (4955 1455);
DISPLAY INVISIBLE (4955 1455);
FORCEPROP 1 LAST OFFPAGE TRUE
J 0
(5325 1425);
DISPLAY 1.170213 (5325 1425);
PAINT GREEN (5325 1425);
DISPLAY INVISIBLE (5325 1425);
FORCEPROP 2 LAST PATH I63
J 0
(5200 1600);
DISPLAY 1.021277 (5200 1600);
PAINT ORANGE (5200 1600);
DISPLAY INVISIBLE (5200 1600);
FORCEPROP 2 LAST CDS_LIB mstr_standard
J 0
(5000 1550);
PAINT ORANGE (5000 1550);
DISPLAY INVISIBLE (5000 1550);
FORCEPROP 2 LAST ROOM VDDQ_ABC_PWR_VR
J 0
(4575 1625);
DISPLAY 1.361702 (4575 1625);
PAINT ORANGE (4575 1625);
DISPLAY INVISIBLE (4575 1625);
FORCEADD OFFPAGE..3
(5000 1800);
FORCEPROP 2 LAST $XR11 235 
J 0
(5694 1764);
DISPLAY 0.638298 (5694 1764);
PAINT MONO (5694 1764);
FORCEPROP 2 LAST $XR10 226 
J 0
(5574 1764);
DISPLAY 0.638298 (5574 1764);
PAINT MONO (5574 1764);
FORCEPROP 2 LAST $XR9 223 
J 0
(5454 1764);
DISPLAY 0.638298 (5454 1764);
PAINT MONO (5454 1764);
FORCEPROP 2 LAST $XR8 218 
J 0
(5334 1764);
DISPLAY 0.638298 (5334 1764);
PAINT MONO (5334 1764);
FORCEPROP 2 LAST $XR7 213 
J 0
(5214 1764);
DISPLAY 0.638298 (5214 1764);
PAINT MONO (5214 1764);
FORCEPROP 2 LAST $XR6 211 
J 0
(5934 1800);
DISPLAY 0.638298 (5934 1800);
PAINT MONO (5934 1800);
FORCEPROP 2 LAST $XR5 206 
J 0
(5814 1800);
DISPLAY 0.638298 (5814 1800);
PAINT MONO (5814 1800);
FORCEPROP 2 LAST $XR4 201 
J 0
(5694 1800);
DISPLAY 0.638298 (5694 1800);
PAINT MONO (5694 1800);
FORCEPROP 2 LAST $XR3 194 
J 0
(5574 1800);
DISPLAY 0.638298 (5574 1800);
PAINT MONO (5574 1800);
FORCEPROP 2 LAST $XR2 193 
J 0
(5454 1800);
DISPLAY 0.638298 (5454 1800);
PAINT MONO (5454 1800);
FORCEPROP 2 LAST $XR1 159 
J 0
(5334 1800);
DISPLAY 0.638298 (5334 1800);
PAINT MONO (5334 1800);
FORCEPROP 2 LAST $XR0 138 
J 0
(5214 1800);
DISPLAY 0.638298 (5214 1800);
PAINT MONO (5214 1800);
FORCEPROP 1 LAST COMMENT_BODY TRUE
J 0
(4950 1700);
DISPLAY 1.170213 (4950 1700);
PAINT GREEN (4950 1700);
DISPLAY INVISIBLE (4950 1700);
FORCEPROP 1 LAST OFFPAGE TRUE
J 0
(5325 1675);
DISPLAY 1.170213 (5325 1675);
PAINT GREEN (5325 1675);
DISPLAY INVISIBLE (5325 1675);
FORCEPROP 2 LAST PATH I64
J 0
(5950 1850);
DISPLAY 1.021277 (5950 1850);
PAINT ORANGE (5950 1850);
DISPLAY INVISIBLE (5950 1850);
FORCEPROP 2 LAST CDS_LIB mstr_standard
J 0
(5000 1800);
PAINT ORANGE (5000 1800);
DISPLAY INVISIBLE (5000 1800);
FORCEPROP 2 LAST ROOM VDDQ_ABC_PWR_VR
J 0
(4600 1875);
DISPLAY 1.361702 (4600 1875);
PAINT ORANGE (4600 1875);
DISPLAY INVISIBLE (4600 1875);
FORCEADD OFFPAGE..1
R 2
(5000 1850);
FORCEPROP 2 LAST $XR11 226 
J 0
(5186 1886);
DISPLAY 0.638298 (5186 1886);
PAINT MONO (5186 1886);
FORCEPROP 2 LAST $XR10 223 
J 0
(6146 1814);
DISPLAY 0.638298 (6146 1814);
PAINT MONO (6146 1814);
FORCEPROP 2 LAST $XR9 218 
J 0
(6026 1814);
DISPLAY 0.638298 (6026 1814);
PAINT MONO (6026 1814);
FORCEPROP 2 LAST $XR8 206 
J 0
(6146 1850);
DISPLAY 0.638298 (6146 1850);
PAINT MONO (6146 1850);
FORCEPROP 2 LAST $XR7 201 
J 0
(6026 1850);
DISPLAY 0.638298 (6026 1850);
PAINT MONO (6026 1850);
FORCEPROP 2 LAST $XR6 194 
J 0
(5906 1850);
DISPLAY 0.638298 (5906 1850);
PAINT MONO (5906 1850);
FORCEPROP 2 LAST $XR5 193 
J 0
(5786 1850);
DISPLAY 0.638298 (5786 1850);
PAINT MONO (5786 1850);
FORCEPROP 2 LAST $XR4 235 
J 0
(5666 1850);
DISPLAY 0.638298 (5666 1850);
PAINT MONO (5666 1850);
FORCEPROP 2 LAST $XR3 213 
J 0
(5546 1850);
DISPLAY 0.638298 (5546 1850);
PAINT MONO (5546 1850);
FORCEPROP 2 LAST $XR2 211 
J 0
(5426 1850);
DISPLAY 0.638298 (5426 1850);
PAINT MONO (5426 1850);
FORCEPROP 2 LAST $XR1 159 
J 0
(5306 1850);
DISPLAY 0.638298 (5306 1850);
PAINT MONO (5306 1850);
FORCEPROP 2 LAST $XR0 138 
J 0
(5186 1850);
DISPLAY 0.638298 (5186 1850);
PAINT MONO (5186 1850);
FORCEPROP 1 LAST COMMENT_BODY TRUE
J 2
(4875 1750);
DISPLAY 1.170213 (4875 1750);
PAINT GREEN (4875 1750);
DISPLAY INVISIBLE (4875 1750);
FORCEPROP 1 LAST OFFPAGE TRUE
J 2
(4675 1725);
DISPLAY 1.170213 (4675 1725);
PAINT GREEN (4675 1725);
DISPLAY INVISIBLE (4675 1725);
FORCEPROP 2 LAST PATH I65
J 0
(5200 1925);
DISPLAY 1.021277 (5200 1925);
PAINT ORANGE (5200 1925);
DISPLAY INVISIBLE (5200 1925);
FORCEPROP 2 LAST CDS_LIB mstr_standard
J 0
(5000 1850);
PAINT ORANGE (5000 1850);
DISPLAY INVISIBLE (5000 1850);
FORCEPROP 2 LAST ROOM VDDQ_ABC_PWR_VR
J 0
(4575 1925);
DISPLAY 1.361702 (4575 1925);
PAINT ORANGE (4575 1925);
DISPLAY INVISIBLE (4575 1925);
FORCEADD OFFPAGE..2
(5000 2200);
FORCEPROP 2 LAST $XR2 21 
J 0
(5429 2200);
DISPLAY 0.638298 (5429 2200);
PAINT MONO (5429 2200);
FORCEPROP 2 LAST $XR1 218 
J 0
(5309 2200);
DISPLAY 0.638298 (5309 2200);
PAINT MONO (5309 2200);
FORCEPROP 2 LAST $XR0 194 
J 0
(5189 2200);
DISPLAY 0.638298 (5189 2200);
PAINT MONO (5189 2200);
FORCEPROP 1 LAST COMMENT_BODY TRUE
J 0
(4955 2105);
DISPLAY 1.170213 (4955 2105);
PAINT GREEN (4955 2105);
DISPLAY INVISIBLE (4955 2105);
FORCEPROP 1 LAST OFFPAGE TRUE
J 0
(5325 2075);
DISPLAY 1.170213 (5325 2075);
PAINT GREEN (5325 2075);
DISPLAY INVISIBLE (5325 2075);
FORCEPROP 2 LAST PATH I66
J 0
(5450 2250);
DISPLAY 1.021277 (5450 2250);
PAINT ORANGE (5450 2250);
DISPLAY INVISIBLE (5450 2250);
FORCEPROP 2 LAST CDS_LIB mstr_standard
J 0
(5000 2200);
PAINT ORANGE (5000 2200);
DISPLAY INVISIBLE (5000 2200);
FORCEPROP 2 LAST ROOM VDDQ_ABC_PWR_VR
J 0
(4575 2275);
DISPLAY 1.361702 (4575 2275);
PAINT ORANGE (4575 2275);
DISPLAY INVISIBLE (4575 2275);
FORCEADD OFFPAGE..2
(5000 2250);
FORCEPROP 2 LAST $XR2 145 
J 0
(5399 2250);
DISPLAY 0.638298 (5399 2250);
PAINT MONO (5399 2250);
FORCEPROP 2 LAST $XR1 119 
J 0
(5279 2250);
DISPLAY 0.638298 (5279 2250);
PAINT MONO (5279 2250);
FORCEPROP 2 LAST $XR0 94 
J 0
(5189 2250);
DISPLAY 0.638298 (5189 2250);
PAINT MONO (5189 2250);
FORCEPROP 1 LAST COMMENT_BODY TRUE
J 0
(4955 2155);
DISPLAY 1.170213 (4955 2155);
PAINT GREEN (4955 2155);
DISPLAY INVISIBLE (4955 2155);
FORCEPROP 1 LAST OFFPAGE TRUE
J 0
(5325 2125);
DISPLAY 1.170213 (5325 2125);
PAINT GREEN (5325 2125);
DISPLAY INVISIBLE (5325 2125);
FORCEPROP 2 LAST PATH I67
J 0
(5400 2300);
DISPLAY 1.021277 (5400 2300);
PAINT ORANGE (5400 2300);
DISPLAY INVISIBLE (5400 2300);
FORCEPROP 2 LAST CDS_LIB mstr_standard
J 0
(5000 2250);
PAINT ORANGE (5000 2250);
DISPLAY INVISIBLE (5000 2250);
FORCEPROP 2 LAST ROOM VDDQ_ABC_PWR_VR
J 0
(4575 2325);
DISPLAY 1.361702 (4575 2325);
PAINT ORANGE (4575 2325);
DISPLAY INVISIBLE (4575 2325);
FORCEADD OFFPAGE..2
(5000 2350);
FORCEPROP 2 LAST $XR0 197 
J 0
(5189 2350);
DISPLAY 0.638298 (5189 2350);
PAINT MONO (5189 2350);
FORCEPROP 1 LAST COMMENT_BODY TRUE
J 0
(4955 2255);
DISPLAY 1.170213 (4955 2255);
PAINT GREEN (4955 2255);
DISPLAY INVISIBLE (4955 2255);
FORCEPROP 1 LAST OFFPAGE TRUE
J 0
(5325 2225);
DISPLAY 1.170213 (5325 2225);
PAINT GREEN (5325 2225);
DISPLAY INVISIBLE (5325 2225);
FORCEPROP 2 LAST PATH I68
J 0
(5200 2400);
DISPLAY 1.021277 (5200 2400);
PAINT ORANGE (5200 2400);
DISPLAY INVISIBLE (5200 2400);
FORCEPROP 2 LAST ROOM VDDQ_ABC_PWR_VR
J 0
(4575 2425);
DISPLAY 1.361702 (4575 2425);
PAINT ORANGE (4575 2425);
DISPLAY INVISIBLE (4575 2425);
FORCEPROP 2 LAST CDS_LIB mstr_standard
J 0
(5000 2350);
PAINT ORANGE (5000 2350);
DISPLAY INVISIBLE (5000 2350);
FORCEADD PXM1310B..2
(2275 1600);
FORCEPROP 2 LASTPIN (1825 1550) $PN 34
J 2
(1815 1560);
DISPLAY 0.617021 (1815 1560);
PAINT MONO (1815 1560);
FORCEPROP 2 LASTPIN (1825 1150) $PN 30
J 2
(1815 1160);
DISPLAY 0.617021 (1815 1160);
PAINT MONO (1815 1160);
FORCEPROP 2 LASTPIN (1825 1200) $PN 20
J 2
(1815 1210);
DISPLAY 0.617021 (1815 1210);
PAINT MONO (1815 1210);
FORCEPROP 2 LASTPIN (1825 1300) $PN 10
J 2
(1815 1310);
DISPLAY 0.617021 (1815 1310);
PAINT MONO (1815 1310);
FORCEPROP 2 LASTPIN (1825 1900) $PN 24
J 2
(1815 1910);
DISPLAY 0.617021 (1815 1910);
PAINT MONO (1815 1910);
FORCEPROP 2 LASTPIN (1825 1850) $PN 26
J 2
(1815 1860);
DISPLAY 0.617021 (1815 1860);
PAINT MONO (1815 1860);
FORCEPROP 2 LASTPIN (1825 1750) $PN 37
J 2
(1815 1760);
DISPLAY 0.617021 (1815 1760);
PAINT MONO (1815 1760);
FORCEPROP 2 LASTPIN (2725 800) $PN 27
J 0
(2735 810);
DISPLAY 0.617021 (2735 810);
PAINT MONO (2735 810);
FORCEPROP 2 LASTPIN (2725 2050) $PN 18
J 0
(2735 2060);
DISPLAY 0.617021 (2735 2060);
PAINT MONO (2735 2060);
FORCEPROP 2 LASTPIN (2725 1050) $PN 28
J 0
(2735 1060);
DISPLAY 0.617021 (2735 1060);
PAINT MONO (2735 1060);
FORCEPROP 2 LASTPIN (2725 900) $PN 41
J 0
(2735 910);
DISPLAY 0.617021 (2735 910);
PAINT MONO (2735 910);
FORCEPROP 2 LASTPIN (1825 800) $PN 36
J 2
(1815 810);
DISPLAY 0.617021 (1815 810);
PAINT MONO (1815 810);
FORCEPROP 2 LASTPIN (1825 1400) $PN 29
J 2
(1815 1410);
DISPLAY 0.617021 (1815 1410);
PAINT MONO (1815 1410);
FORCEPROP 2 LASTPIN (1825 1600) $PN 35
J 2
(1815 1610);
DISPLAY 0.617021 (1815 1610);
PAINT MONO (1815 1610);
FORCEPROP 2 LASTPIN (2725 1000) $PN 2
J 0
(2735 1010);
DISPLAY 0.617021 (2735 1010);
PAINT MONO (2735 1010);
FORCEPROP 2 LASTPIN (2725 1300) $PN 5
J 0
(2735 1310);
DISPLAY 0.617021 (2735 1310);
PAINT MONO (2735 1310);
FORCEPROP 2 LASTPIN (2725 1850) $PN 7
J 0
(2735 1860);
DISPLAY 0.617021 (2735 1860);
PAINT MONO (2735 1860);
FORCEPROP 2 LASTPIN (2725 1800) $PN 6
J 0
(2735 1810);
DISPLAY 0.617021 (2735 1810);
PAINT MONO (2735 1810);
FORCEPROP 2 LASTPIN (2725 2200) $PN 17
J 0
(2735 2210);
DISPLAY 0.617021 (2735 2210);
PAINT MONO (2735 2210);
FORCEPROP 2 LASTPIN (2725 2250) $PN 11
J 0
(2735 2260);
DISPLAY 0.617021 (2735 2260);
PAINT MONO (2735 2260);
FORCEPROP 2 LASTPIN (1825 1450) $PN 19
J 2
(1815 1460);
DISPLAY 0.617021 (1815 1460);
PAINT MONO (1815 1460);
FORCEPROP 2 LASTPIN (2725 2350) $PN 9
J 0
(2735 2360);
DISPLAY 0.617021 (2735 2360);
PAINT MONO (2735 2360);
FORCEPROP 2 LASTPIN (2725 1700) $PN 13
J 0
(2735 1710);
DISPLAY 0.617021 (2735 1710);
PAINT MONO (2735 1710);
FORCEPROP 2 LASTPIN (2725 1550) $PN 40
J 0
(2735 1560);
DISPLAY 0.617021 (2735 1560);
PAINT MONO (2735 1560);
FORCEPROP 2 LASTPIN (1825 2050) $PN 25
J 2
(1815 2060);
DISPLAY 0.617021 (1815 2060);
PAINT MONO (1815 2060);
FORCEPROP 2 LASTPIN (1825 2100) $PN 23
J 2
(1815 2110);
DISPLAY 0.617021 (1815 2110);
PAINT MONO (1815 2110);
FORCEPROP 2 LASTPIN (2725 1650) $PN 14
J 0
(2735 1660);
DISPLAY 0.617021 (2735 1660);
PAINT MONO (2735 1660);
FORCEPROP 2 LASTPIN (2725 1500) $PN 16
J 0
(2735 1510);
DISPLAY 0.617021 (2735 1510);
PAINT MONO (2735 1510);
FORCEPROP 2 LASTPIN (1825 1700) $PN 38
J 2
(1815 1710);
DISPLAY 0.617021 (1815 1710);
PAINT MONO (1815 1710);
FORCEPROP 2 LASTPIN (2725 1950) $PN 12
J 0
(2735 1960);
DISPLAY 0.617021 (2735 1960);
PAINT MONO (2735 1960);
FORCEPROP 2 LASTPIN (1825 1950) $PN 22
J 2
(1815 1960);
DISPLAY 0.617021 (1815 1960);
PAINT MONO (1815 1960);
FORCEPROP 2 LASTPIN (1825 2350) $PN 39
J 2
(1815 2360);
DISPLAY 0.617021 (1815 2360);
PAINT MONO (1815 2360);
FORCEPROP 2 LASTPIN (1825 1050) $PN 8
J 2
(1815 1060);
DISPLAY 0.617021 (1815 1060);
PAINT MONO (1815 1060);
FORCEPROP 2 LASTPIN (1825 950) $PN 31
J 2
(1815 960);
DISPLAY 0.617021 (1815 960);
PAINT MONO (1815 960);
FORCEPROP 2 LASTPIN (1825 750) $PN 33
J 2
(1815 760);
DISPLAY 0.617021 (1815 760);
PAINT MONO (1815 760);
FORCEPROP 2 LASTPIN (1825 900) $PN 32
J 2
(1815 910);
DISPLAY 0.617021 (1815 910);
PAINT MONO (1815 910);
FORCEPROP 1 LAST PART_NUMBER H89186-001
J 0
(1875 650);
DISPLAY 0.617021 (1875 650);
PAINT BLUE (1875 650);
FORCEPROP 2 LASTPIN (2725 1200) $PN 3
J 0
(2735 1210);
DISPLAY 0.617021 (2735 1210);
PAINT MONO (2735 1210);
FORCEPROP 2 LASTPIN (2725 1250) $PN 4
J 0
(2735 1260);
DISPLAY 0.617021 (2735 1260);
PAINT MONO (2735 1260);
FORCEPROP 2 LASTPIN (2725 1350) $PN 1
J 0
(2735 1360);
DISPLAY 0.617021 (2735 1360);
PAINT MONO (2735 1360);
FORCEPROP 2 LASTPIN (1825 2250) $PN 15
J 2
(1815 2260);
DISPLAY 0.617021 (1815 2260);
PAINT MONO (1815 2260);
FORCEPROP 2 LASTPIN (1825 2150) $PN 21
J 2
(1815 2160);
DISPLAY 0.617021 (1815 2160);
PAINT MONO (1815 2160);
FORCEPROP 1 LAST LOCATION EU7G1
J 0
(1875 2575);
DISPLAY 0.617021 (1875 2575);
PAINT AQUA (1875 2575);
FORCEPROP 1 LAST MATERIAL IC
J 0
(1875 2525);
DISPLAY 0.617021 (1875 2525);
PAINT SKYBLUE (1875 2525);
FORCEPROP 1 LAST PATH I69
J 0
(2375 2526);
PAINT WHITE (2375 2526);
DISPLAY INVISIBLE (2375 2526);
FORCEPROP 1 LAST CDS_LMAN_SYM_OUTLINE -400,900,400,-900
J 0
(2275 1600);
DISPLAY 0.468085 (2275 1600);
PAINT GREEN (2275 1600);
DISPLAY INVISIBLE (2275 1600);
FORCEPROP 2 LAST CDS_LIB mstr_controller
J 0
(2275 1600);
PAINT ORANGE (2275 1600);
DISPLAY INVISIBLE (2275 1600);
FORCEPROP 1 LAST PACK_TYPE QFN
J 0
(1875 2625);
PAINT SKYBLUE (1875 2625);
DISPLAY INVISIBLE (1875 2625);
FORCEPROP 2 LAST CDS_SEC 1
J 0
(1875 2625);
PAINT MONO (1875 2625);
DISPLAY INVISIBLE (1875 2625);
FORCEPROP 2 LAST $SEC 1
J 0
(1875 2625);
PAINT MONO (1875 2625);
DISPLAY INVISIBLE (1875 2625);
FORCEPROP 2 LAST CDS_LOCATION EU7G1
J 0
(1875 2575);
PAINT WHITE (1875 2575);
DISPLAY INVISIBLE (1875 2575);
FORCEADD OFFPAGE..1
(-1400 1900);
FORCEPROP 2 LASTPIN (-1350 1900) SIG_NAME ISENSE_PVDDQ_ABC_PH2_IMON
J 0
(-1355 1915);
DISPLAY 0.617021 (-1355 1915);
PAINT ORANGE (-1355 1915);
FORCEPROP 2 LAST $XR0 216 
J 0
(-1652 1900);
DISPLAY 0.638298 (-1652 1900);
PAINT MONO (-1652 1900);
FORCEPROP 1 LAST COMMENT_BODY TRUE
J 0
(-1275 1800);
DISPLAY 1.170213 (-1275 1800);
PAINT GREEN (-1275 1800);
DISPLAY INVISIBLE (-1275 1800);
FORCEPROP 1 LAST OFFPAGE TRUE
J 0
(-1075 1775);
DISPLAY 1.170213 (-1075 1775);
PAINT GREEN (-1075 1775);
DISPLAY INVISIBLE (-1075 1775);
FORCEPROP 2 LAST PATH I7
J 0
(-1650 1950);
DISPLAY 1.021277 (-1650 1950);
PAINT ORANGE (-1650 1950);
DISPLAY INVISIBLE (-1650 1950);
FORCEPROP 2 LAST ROOM VDDQ_ABC_PWR_VR
J 0
(-1950 1975);
DISPLAY 1.361702 (-1950 1975);
PAINT ORANGE (-1950 1975);
DISPLAY INVISIBLE (-1950 1975);
FORCEPROP 2 LAST CDS_LIB mstr_standard
J 0
(-1400 1900);
PAINT ORANGE (-1400 1900);
DISPLAY INVISIBLE (-1400 1900);
FORCEADD RES..2
(450 3325);
FORCEPROP 1 LAST VALUE 49.9
J 0
(495 3400);
DISPLAY 0.617021 (495 3400);
PAINT SKYBLUE (495 3400);
FORCEPROP 1 LAST PACK_TYPE 0402
J 0
(490 3150);
DISPLAY 0.617021 (490 3150);
PAINT SKYBLUE (490 3150);
FORCEPROP 1 LASTPIN (450 3225) $PN 2
J 0
(455 3235);
DISPLAY 0.617021 (455 3235);
PAINT ORANGE (455 3235);
FORCEPROP 1 LAST MATERIAL CHIP
J 0
(490 3250);
DISPLAY 0.638298 (490 3250);
PAINT SKYBLUE (490 3250);
FORCEPROP 1 LAST WATTAGE 1/16W
J 0
(490 3300);
DISPLAY 0.617021 (490 3300);
PAINT SKYBLUE (490 3300);
FORCEPROP 1 LAST TOLERANCE 1%
J 0
(495 3350);
DISPLAY 0.617021 (495 3350);
PAINT SKYBLUE (495 3350);
FORCEPROP 1 LASTPIN (450 3425) $PN 1
J 0
(455 3387);
DISPLAY 0.617021 (455 3387);
PAINT ORANGE (455 3387);
FORCEPROP 1 LAST PART_NUMBER G21796-047
J 0
(490 3200);
DISPLAY 0.617021 (490 3200);
PAINT BLUE (490 3200);
FORCEPROP 1 LAST LOCATION R3T11
J 0
(495 3450);
DISPLAY 0.617021 (495 3450);
PAINT AQUA (495 3450);
FORCEPROP 2 LAST SEC_TYPE 0402
J 0
(500 3575);
DISPLAY 1.021277 (500 3575);
PAINT ORANGE (500 3575);
DISPLAY INVISIBLE (500 3575);
FORCEPROP 2 LAST SEC 1
J 0
(500 3575);
PAINT MONO (500 3575);
DISPLAY INVISIBLE (500 3575);
FORCEPROP 2 LAST CDS_LIB mstr_discrete
J 0
(450 3325);
PAINT ORANGE (450 3325);
DISPLAY INVISIBLE (450 3325);
FORCEPROP 2 LAST ROOM VDDQ_DEF_PWR_VR
J 0
(500 3500);
DISPLAY 1.361702 (500 3500);
PAINT ORANGE (500 3500);
DISPLAY INVISIBLE (500 3500);
FORCEPROP 0 LAST CDS_SEC 1
J 0
(500 3500);
PAINT MONO (500 3500);
DISPLAY INVISIBLE (500 3500);
FORCEPROP 1 LAST PATH I70
J 0
(500 3500);
DISPLAY 0.978723 (500 3500);
PAINT WHITE (500 3500);
DISPLAY INVISIBLE (500 3500);
FORCEPROP 2 LAST CDS_LOCATION R3T11
J 0
(495 3450);
DISPLAY 0.617021 (495 3450);
PAINT AQUA (495 3450);
DISPLAY INVISIBLE (495 3450);
FORCEADD RES..2
(1050 -50);
FORCEPROP 1 LASTPIN (1050 -150) $PN 2
J 0
(1055 -140);
DISPLAY 0.787234 (1055 -140);
PAINT ORANGE (1055 -140);
FORCEPROP 1 LAST MATERIAL CHIP
J 0
(1090 -125);
DISPLAY 0.617021 (1090 -125);
PAINT SKYBLUE (1090 -125);
FORCEPROP 1 LAST WATTAGE 1/16W
J 0
(1090 -75);
DISPLAY 0.617021 (1090 -75);
PAINT SKYBLUE (1090 -75);
FORCEPROP 1 LAST VALUE 2.26K
J 0
(1095 25);
DISPLAY 0.617021 (1095 25);
PAINT SKYBLUE (1095 25);
FORCEPROP 1 LASTPIN (1050 50) $PN 1
J 0
(1055 12);
DISPLAY 0.787234 (1055 12);
PAINT ORANGE (1055 12);
FORCEPROP 1 LAST PACK_TYPE 0402
J 0
(1090 -225);
DISPLAY 0.617021 (1090 -225);
PAINT SKYBLUE (1090 -225);
FORCEPROP 1 LAST TOLERANCE 1.0%
J 0
(1095 -25);
DISPLAY 0.617021 (1095 -25);
PAINT SKYBLUE (1095 -25);
FORCEPROP 0 LAST POP NOPOP
J 0
(1100 -275);
DISPLAY 0.638298 (1100 -275);
PAINT RED (1100 -275);
FORCEPROP 1 LAST PART_NUMBER G21796-311
J 0
(1090 -175);
DISPLAY 0.617021 (1090 -175);
PAINT BLUE (1090 -175);
FORCEPROP 1 LAST LOCATION R7G8
J 0
(1095 75);
DISPLAY 0.617021 (1095 75);
PAINT AQUA (1095 75);
FORCEPROP 1 LAST PATH I72
J 0
(1100 125);
DISPLAY 0.978723 (1100 125);
PAINT WHITE (1100 125);
DISPLAY INVISIBLE (1100 125);
FORCEPROP 2 LAST CDS_LOCATION R7G8
J 0
(1095 75);
DISPLAY 0.617021 (1095 75);
PAINT AQUA (1095 75);
DISPLAY INVISIBLE (1095 75);
FORCEPROP 2 LAST CDS_LIB mstr_discrete
J 0
(1050 -50);
PAINT ORANGE (1050 -50);
DISPLAY INVISIBLE (1050 -50);
FORCEPROP 0 LAST SKU B
J 0
(1100 175);
DISPLAY 1.021277 (1100 175);
PAINT ORANGE (1100 175);
DISPLAY INVISIBLE (1100 175);
FORCEPROP 0 LAST ROOM SMBUS
J 0
(1100 175);
DISPLAY 1.021277 (1100 175);
PAINT ORANGE (1100 175);
DISPLAY INVISIBLE (1100 175);
FORCEPROP 0 LAST BOM_COST SM_CONTROLLER
J 0
(1100 275);
DISPLAY 1.021277 (1100 275);
PAINT ORANGE (1100 275);
DISPLAY INVISIBLE (1100 275);
FORCEPROP 2 LAST SEC 1
J 0
(1100 175);
PAINT MONO (1100 175);
DISPLAY INVISIBLE (1100 175);
FORCEPROP 2 LAST SEC_TYPE 0402
J 0
(1100 175);
DISPLAY 1.021277 (1100 175);
PAINT ORANGE (1100 175);
DISPLAY INVISIBLE (1100 175);
FORCEADD RES..2
(1400 -50);
FORCEPROP 1 LAST VALUE 2.26K
J 0
(1445 25);
DISPLAY 0.617021 (1445 25);
PAINT SKYBLUE (1445 25);
FORCEPROP 1 LAST PACK_TYPE 0402
J 0
(1440 -225);
DISPLAY 0.617021 (1440 -225);
PAINT SKYBLUE (1440 -225);
FORCEPROP 1 LASTPIN (1400 50) $PN 1
J 0
(1405 12);
DISPLAY 0.787234 (1405 12);
PAINT ORANGE (1405 12);
FORCEPROP 1 LASTPIN (1400 -150) $PN 2
J 0
(1405 -140);
DISPLAY 0.787234 (1405 -140);
PAINT ORANGE (1405 -140);
FORCEPROP 1 LAST LOCATION R7G10
J 0
(1445 75);
DISPLAY 0.617021 (1445 75);
PAINT AQUA (1445 75);
FORCEPROP 1 LAST WATTAGE 1/16W
J 0
(1440 -75);
DISPLAY 0.617021 (1440 -75);
PAINT SKYBLUE (1440 -75);
FORCEPROP 1 LAST TOLERANCE 1.0%
J 0
(1445 -25);
DISPLAY 0.617021 (1445 -25);
PAINT SKYBLUE (1445 -25);
FORCEPROP 1 LAST MATERIAL CHIP
J 0
(1440 -125);
DISPLAY 0.617021 (1440 -125);
PAINT SKYBLUE (1440 -125);
FORCEPROP 1 LAST PART_NUMBER G21796-311
J 0
(1440 -175);
DISPLAY 0.617021 (1440 -175);
PAINT BLUE (1440 -175);
FORCEPROP 2 LAST CDS_LIB mstr_discrete
J 0
(1400 -50);
PAINT ORANGE (1400 -50);
DISPLAY INVISIBLE (1400 -50);
FORCEPROP 0 LAST SKU B
J 0
(1450 175);
DISPLAY 1.021277 (1450 175);
PAINT ORANGE (1450 175);
DISPLAY INVISIBLE (1450 175);
FORCEPROP 0 LAST ROOM SMBUS
J 0
(1450 175);
DISPLAY 1.021277 (1450 175);
PAINT ORANGE (1450 175);
DISPLAY INVISIBLE (1450 175);
FORCEPROP 0 LAST BOM_COST SM_CONTROLLER
J 0
(1450 275);
DISPLAY 1.021277 (1450 275);
PAINT ORANGE (1450 275);
DISPLAY INVISIBLE (1450 275);
FORCEPROP 2 LAST SEC 1
J 0
(1450 175);
PAINT MONO (1450 175);
DISPLAY INVISIBLE (1450 175);
FORCEPROP 2 LAST SEC_TYPE 0402
J 0
(1450 175);
DISPLAY 1.021277 (1450 175);
PAINT ORANGE (1450 175);
DISPLAY INVISIBLE (1450 175);
FORCEPROP 1 LAST PATH I73
J 0
(1450 125);
DISPLAY 0.978723 (1450 125);
PAINT WHITE (1450 125);
DISPLAY INVISIBLE (1450 125);
FORCEPROP 2 LAST CDS_LOCATION R7G10
J 0
(1445 75);
DISPLAY 0.617021 (1445 75);
PAINT AQUA (1445 75);
DISPLAY INVISIBLE (1445 75);
FORCEADD RES..1
(4000 1700);
FORCEPROP 1 LAST WATTAGE 1/16W
J 0
(4450 1700);
DISPLAY 0.510638 (4450 1700);
PAINT SKYBLUE (4450 1700);
FORCEPROP 1 LAST PACK_TYPE 0402
J 0
(4350 1700);
DISPLAY 0.617021 (4350 1700);
PAINT SKYBLUE (4350 1700);
FORCEPROP 1 LAST LOCATION R12W25
J 0
(3500 1700);
DISPLAY 0.617021 (3500 1700);
PAINT AQUA (3500 1700);
FORCEPROP 1 LAST TOLERANCE 5%
J 0
(4200 1700);
DISPLAY 0.617021 (4200 1700);
PAINT SKYBLUE (4200 1700);
FORCEPROP 1 LASTPIN (3900 1700) $PN 1
J 0
(3912 1712);
DISPLAY 0.617021 (3912 1712);
PAINT WHITE (3912 1712);
FORCEPROP 1 LASTPIN (4100 1700) $PN 2
J 0
(4062 1712);
DISPLAY 0.617021 (4062 1712);
PAINT WHITE (4062 1712);
FORCEPROP 1 LAST VALUE 0.0
J 0
(4125 1700);
DISPLAY 0.617021 (4125 1700);
PAINT SKYBLUE (4125 1700);
FORCEPROP 1 LAST PART_NUMBER G21497-005
J 0
(3675 1700);
DISPLAY 0.617021 (3675 1700);
PAINT BLUE (3675 1700);
FORCEPROP 1 LAST PATH I74
J 0
(3950 1850);
DISPLAY 0.978723 (3950 1850);
PAINT WHITE (3950 1850);
DISPLAY INVISIBLE (3950 1850);
FORCEPROP 2 LAST CDS_LIB mstr_discrete
J 0
(4000 1700);
DISPLAY 1.340426 (4000 1700);
PAINT ORANGE (4000 1700);
DISPLAY INVISIBLE (4000 1700);
FORCEPROP 2 LAST BOM_COST PROC_SIDEBAND
J 0
(4000 1700);
PAINT MONO (4000 1700);
DISPLAY INVISIBLE (4000 1700);
FORCEPROP 1 LAST MATERIAL CHIP
J 0
(4150 1600);
DISPLAY 0.510638 (4150 1600);
PAINT SKYBLUE (4150 1600);
DISPLAY INVISIBLE (4150 1600);
FORCEPROP 2 LAST ROOM CPU0
J 0
(3950 1850);
PAINT PEACH (3950 1850);
DISPLAY INVISIBLE (3950 1850);
FORCEPROP 2 LAST SEC_TYPE 0402
J 0
(3950 1925);
DISPLAY 1.021277 (3950 1925);
PAINT ORANGE (3950 1925);
DISPLAY INVISIBLE (3950 1925);
FORCEPROP 2 LAST SEC 1
J 0
(3950 1925);
DISPLAY 0.680851 (3950 1925);
PAINT MONO (3950 1925);
DISPLAY INVISIBLE (3950 1925);
FORCEPROP 2 LAST CDS_LOCATION R12W25
J 0
(3525 1700);
DISPLAY 0.617021 (3525 1700);
PAINT AQUA (3525 1700);
DISPLAY INVISIBLE (3525 1700);
FORCEADD RES..2
(4300 2900);
FORCEPROP 1 LAST PART_NUMBER G21796-311
J 0
(4340 2775);
DISPLAY 0.617021 (4340 2775);
PAINT BLUE (4340 2775);
FORCEPROP 1 LAST TOLERANCE 1.0%
J 0
(4345 2925);
DISPLAY 0.617021 (4345 2925);
PAINT SKYBLUE (4345 2925);
FORCEPROP 1 LAST PACK_TYPE 0402
J 0
(4340 2725);
DISPLAY 0.617021 (4340 2725);
PAINT SKYBLUE (4340 2725);
FORCEPROP 1 LAST LOCATION R7F36
J 0
(4345 3025);
DISPLAY 0.617021 (4345 3025);
PAINT AQUA (4345 3025);
FORCEPROP 1 LASTPIN (4300 3000) $PN 1
J 0
(4305 2962);
DISPLAY 0.787234 (4305 2962);
PAINT ORANGE (4305 2962);
FORCEPROP 1 LAST VALUE 2.26K
J 0
(4345 2975);
DISPLAY 0.617021 (4345 2975);
PAINT SKYBLUE (4345 2975);
FORCEPROP 1 LAST MATERIAL CHIP
J 0
(4340 2825);
DISPLAY 0.617021 (4340 2825);
PAINT SKYBLUE (4340 2825);
FORCEPROP 1 LASTPIN (4300 2800) $PN 2
J 0
(4305 2810);
DISPLAY 0.787234 (4305 2810);
PAINT ORANGE (4305 2810);
FORCEPROP 1 LAST WATTAGE 1/16W
J 0
(4340 2875);
DISPLAY 0.617021 (4340 2875);
PAINT SKYBLUE (4340 2875);
FORCEPROP 2 LAST CDS_LIB mstr_discrete
J 0
(4300 2900);
PAINT ORANGE (4300 2900);
DISPLAY INVISIBLE (4300 2900);
FORCEPROP 0 LAST SKU B
J 0
(4350 3125);
DISPLAY 1.021277 (4350 3125);
PAINT ORANGE (4350 3125);
DISPLAY INVISIBLE (4350 3125);
FORCEPROP 0 LAST ROOM SMBUS
J 0
(4350 3125);
DISPLAY 1.021277 (4350 3125);
PAINT ORANGE (4350 3125);
DISPLAY INVISIBLE (4350 3125);
FORCEPROP 0 LAST BOM_COST SM_CONTROLLER
J 0
(4350 3225);
DISPLAY 1.021277 (4350 3225);
PAINT ORANGE (4350 3225);
DISPLAY INVISIBLE (4350 3225);
FORCEPROP 2 LAST SEC 1
J 0
(4350 3125);
PAINT MONO (4350 3125);
DISPLAY INVISIBLE (4350 3125);
FORCEPROP 2 LAST SEC_TYPE 0402
J 0
(4350 3125);
DISPLAY 1.021277 (4350 3125);
PAINT ORANGE (4350 3125);
DISPLAY INVISIBLE (4350 3125);
FORCEPROP 1 LAST PATH I75
J 0
(4350 3075);
DISPLAY 0.978723 (4350 3075);
PAINT WHITE (4350 3075);
DISPLAY INVISIBLE (4350 3075);
FORCEPROP 2 LAST CDS_LOCATION R7F36
J 0
(4345 3025);
DISPLAY 0.617021 (4345 3025);
PAINT AQUA (4345 3025);
DISPLAY INVISIBLE (4345 3025);
FORCEADD OFFPAGE..1
(-1400 1950);
FORCEPROP 2 LASTPIN (-1350 1950) SIG_NAME ISENSE_PVDDQ_ABC_PH1_IMON
J 0
(-1355 1965);
DISPLAY 0.617021 (-1355 1965);
PAINT ORANGE (-1355 1965);
FORCEPROP 2 LAST $XR0 216 
J 0
(-1652 1950);
DISPLAY 0.638298 (-1652 1950);
PAINT MONO (-1652 1950);
FORCEPROP 1 LAST COMMENT_BODY TRUE
J 0
(-1275 1850);
DISPLAY 1.170213 (-1275 1850);
PAINT GREEN (-1275 1850);
DISPLAY INVISIBLE (-1275 1850);
FORCEPROP 1 LAST OFFPAGE TRUE
J 0
(-1075 1825);
DISPLAY 1.170213 (-1075 1825);
PAINT GREEN (-1075 1825);
DISPLAY INVISIBLE (-1075 1825);
FORCEPROP 2 LAST PATH I8
J 0
(-1650 2000);
DISPLAY 1.021277 (-1650 2000);
PAINT ORANGE (-1650 2000);
DISPLAY INVISIBLE (-1650 2000);
FORCEPROP 2 LAST ROOM VDDQ_ABC_PWR_VR
J 0
(-1950 2025);
DISPLAY 1.361702 (-1950 2025);
PAINT ORANGE (-1950 2025);
DISPLAY INVISIBLE (-1950 2025);
FORCEPROP 2 LAST CDS_LIB mstr_standard
J 0
(-1400 1950);
PAINT ORANGE (-1400 1950);
DISPLAY INVISIBLE (-1400 1950);
FORCEADD OFFPAGE..1
(-1400 2100);
FORCEPROP 2 LAST $XR0 216 
J 0
(-1652 2100);
DISPLAY 0.638298 (-1652 2100);
PAINT MONO (-1652 2100);
FORCEPROP 1 LAST COMMENT_BODY TRUE
J 0
(-1275 2000);
DISPLAY 1.170213 (-1275 2000);
PAINT GREEN (-1275 2000);
DISPLAY INVISIBLE (-1275 2000);
FORCEPROP 1 LAST OFFPAGE TRUE
J 0
(-1075 1975);
DISPLAY 1.170213 (-1075 1975);
PAINT GREEN (-1075 1975);
DISPLAY INVISIBLE (-1075 1975);
FORCEPROP 2 LAST PATH I9
J 0
(-1650 2150);
DISPLAY 1.021277 (-1650 2150);
PAINT ORANGE (-1650 2150);
DISPLAY INVISIBLE (-1650 2150);
FORCEPROP 2 LAST ROOM VDDQ_ABC_PWR_VR
J 0
(-1950 2175);
DISPLAY 1.361702 (-1950 2175);
PAINT ORANGE (-1950 2175);
DISPLAY INVISIBLE (-1950 2175);
FORCEPROP 2 LAST CDS_LIB mstr_standard
J 0
(-1400 2100);
PAINT ORANGE (-1400 2100);
DISPLAY INVISIBLE (-1400 2100);
FORCEADD DNS..2
(4005 1595);
PAINT RED (4005 1595);
FORCEPROP 2 LAST CDS_LIB mstr_misc
J 0
(4005 1595);
PAINT ORANGE (4005 1595);
DISPLAY INVISIBLE (4005 1595);
FORCEPROP 1 LAST COMMENT_BODY TRUE
R 1
J 0
(4080 1370);
DISPLAY 0.872340 (4080 1370);
PAINT GREEN (4080 1370);
DISPLAY INVISIBLE (4080 1370);
FORCEADD DNS..2
(1055 -55);
PAINT RED (1055 -55);
FORCEPROP 2 LAST CDS_LIB mstr_misc
J 0
(1055 -55);
PAINT ORANGE (1055 -55);
DISPLAY INVISIBLE (1055 -55);
FORCEPROP 1 LAST COMMENT_BODY TRUE
R 1
J 0
(1130 -280);
DISPLAY 0.872340 (1130 -280);
PAINT GREEN (1130 -280);
DISPLAY INVISIBLE (1130 -280);
FORCEADD DNS..2
(980 3320);
PAINT RED (980 3320);
FORCEPROP 2 LAST CDS_LIB mstr_misc
J 0
(980 3320);
PAINT ORANGE (980 3320);
DISPLAY INVISIBLE (980 3320);
FORCEPROP 1 LAST COMMENT_BODY TRUE
R 1
J 0
(1055 3095);
DISPLAY 0.872340 (1055 3095);
PAINT GREEN (1055 3095);
DISPLAY INVISIBLE (1055 3095);
FORCEADD DESIGN_NOTE..1
(1700 500);
FORCEPROP 0 LAST L1 SMBUS ADDRESS: 0XE0
J 0
(1500 375);
DISPLAY 1.021277 (1500 375);
PAINT VIOLET (1500 375);
FORCEPROP 1 LAST COMMENT_BODY TRUE
J 0
(1725 600);
DISPLAY 0.978723 (1725 600);
PAINT ORANGE (1725 600);
DISPLAY INVISIBLE (1725 600);
FORCEPROP 2 LAST CDS_LIB mstr_symbols
J 0
(1700 500);
PAINT ORANGE (1700 500);
DISPLAY INVISIBLE (1700 500);
FORCEADD DESIGN_NOTE..1
(4400 3850);
PAINT PURPLE (4400 3850);
FORCEPROP 0 LAST L1 SVID ADDRESS
J 0
(4205 3715);
DISPLAY 1.021277 (4205 3715);
PAINT VIOLET (4205 3715);
FORCEPROP 0 LAST L2 PVDDQ_ABC: 0X00(BUS #2)
J 0
(4200 3625);
DISPLAY 1.021277 (4200 3625);
PAINT VIOLET (4200 3625);
FORCEPROP 1 LAST COMMENT_BODY TRUE
J 0
(4425 3950);
DISPLAY 1.319149 (4425 3950);
PAINT GREEN (4425 3950);
DISPLAY INVISIBLE (4425 3950);
FORCEPROP 2 LAST BOM_COST SM_CONTROLLER
J 0
(4200 3800);
PAINT MONO (4200 3800);
DISPLAY INVISIBLE (4200 3800);
FORCEPROP 2 LAST CDS_LIB mstr_symbols
J 0
(4400 3850);
PAINT MONO (4400 3850);
DISPLAY INVISIBLE (4400 3850);
FORCEPROP 2 LAST ROOM VDDQ_ABC_PWR_VR
J 0
(4200 3800);
PAINT MONO (4200 3800);
DISPLAY INVISIBLE (4200 3800);
FORCEADD INTEL_CORP_BPAGE..1
(6125 -1075);
FORCEPROP 1 LAST CDS_CON_LAST_MODIFIED Fri Jun 16 17:49:17 2017
J 0
(4700 -750);
DISPLAY 0.744681 (4700 -750);
PAINT GREEN (4700 -750);
DISPLAY INVISIBLE (4700 -750);
FORCEPROP 1 LAST CUSTOM_TXT_CDS <CURRENT_DESIGN_SHEET> OF <TOTAL_DESIGN_SHEETS>
J 0
(5625 -1050);
PAINT ORANGE (5625 -1050);
FORCEPROP 1 LAST CUSTOM_TXT_CDS <CON_LAST_MODIFIED>
J 0
(2125 -975);
PAINT ORANGE (2125 -975);
FORCEPROP 2 LAST CUSTOM_TXT_CDS <XR_PAGE_TITLE>
J 0
(-1765 4175);
DISPLAY 0.638298 (-1765 4175);
PAINT PINK (-1765 4175);
DISPLAY INVISIBLE (-1765 4175);
FORCEPROP 1 LAST SCH_TITLE VDDQ ABC VR (1 OF 3)
J 0
(-1850 -1050);
DISPLAY 1.212766 (-1850 -1050);
PAINT ORANGE (-1850 -1050);
FORCEPROP 1 LAST COMMENT_BODY TRUE
J 0
(6137 -1063);
DISPLAY 0.340426 (6137 -1063);
PAINT GREEN (6137 -1063);
DISPLAY INVISIBLE (6137 -1063);
FORCEPROP 2 LAST ROOM VDDQ_ABC_PWR_VR
J 0
(5675 4075);
DISPLAY 0.744681 (5675 4075);
PAINT ORANGE (5675 4075);
DISPLAY INVISIBLE (5675 4075);
FORCEPROP 2 LAST CDS_LIB mstr_symbols
J 0
(6125 -1075);
DISPLAY 0.744681 (6125 -1075);
PAINT ORANGE (6125 -1075);
DISPLAY INVISIBLE (6125 -1075);
FORCEPROP 2 LAST PAGE_BORDER TRUE
J 0
(-1765 4175);
DISPLAY 0.638298 (-1765 4175);
PAINT PINK (-1765 4175);
DISPLAY INVISIBLE (-1765 4175);
FORCEPROP 2 LAST CDS_XR_PAGE_TITLE CR-215 : @BASEBOARD_FAB2_LIB.BASEBOARD_FAB2(SCH_1):PAGE215
J 0
(-1765 4175);
DISPLAY 0.638298 (-1765 4175);
PAINT PINK (-1765 4175);
DISPLAY INVISIBLE (-1765 4175);
FORCEADD DNS..2
(4005 2070);
PAINT RED (4005 2070);
FORCEPROP 1 LAST COMMENT_BODY TRUE
R 1
J 0
(4080 1845);
DISPLAY 0.872340 (4080 1845);
PAINT GREEN (4080 1845);
DISPLAY INVISIBLE (4080 1845);
FORCEPROP 2 LAST CDS_LIB mstr_misc
J 0
(4005 2070);
PAINT ORANGE (4005 2070);
DISPLAY INVISIBLE (4005 2070);
WIRE 16 -1 (450 3425)(450 3550);
WIRE 16 -1 (875 -100)(875 450);
WIRE 16 -1 (1050 -250)(1050 -150);
WIRE 16 -1 (950 900)(950 700);
WIRE 16 -1 (1825 900)(950 900);
WIRE 16 -1 (1400 -250)(1400 -150);
WIRE 16 -1 (1675 3575)(1675 3625);
WIRE 16 -1 (975 3575)(1675 3575);
WIRE 16 -1 (1675 3350)(1675 3575);
WIRE 16 -1 (975 3425)(975 3575);
WIRE 16 -1 (1975 2750)(1975 2800);
WIRE 16 -1 (2375 2750)(2375 2800);
WIRE 16 -1 (2850 675)(2850 800);
WIRE 16 -1 (2850 900)(2850 800);
WIRE 16 -1 (2725 800)(2850 800);
WIRE 16 -1 (2725 900)(2850 900);
WIRE 16 -1 (3150 50)(3150 100);
WIRE 16 -1 (3550 -25)(3550 100);
WIRE 16 -1 (3800 950)(3800 825);
WIRE 16 -1 (3500 3350)(3500 3525);
WIRE 16 -1 (3500 3350)(3300 3350);
WIRE 16 -1 (4300 3350)(3500 3350);
WIRE 16 -1 (4300 3000)(4300 3350);
WIRE 16 -1 (2950 3350)(3300 3350);
WIRE 16 -1 (3300 3000)(3300 3350);
WIRE 16 -1 (2950 3000)(2950 3350);
WIRE 16 -1 (4750 2750)(4750 2800);
WIRE 16 -1 (4950 1300)(2725 1300);
FORCEPROP 2 LAST SIG_NAME VR_PVDDQ_ABC_PWM1
J 0
(4250 1315);
DISPLAY 0.617021 (4250 1315);
PAINT ORANGE (4250 1315);
WIRE 16 2175 (4750 3000)(4750 3500);
WIRE 16 2175 (5900 3000)(4750 3000);
WIRE 16 2175 (5900 3500)(4750 3500);
WIRE 16 2175 (5900 3500)(5900 3000);
WIRE 16 -1 (3725 1500)(4750 1500);
FORCEPROP 2 LAST SIG_NAME SVID_DIO1_CPU0_R
J 0
(4175 1510);
DISPLAY 0.617021 (4175 1510);
PAINT ORANGE (4175 1510);
WIRE 16 -1 (4750 1500)(4950 1500);
WIRE 16 -1 (4750 2550)(4750 1500);
WIRE 16 -1 (4300 1650)(4100 1650);
WIRE 16 -1 (4150 2350)(4300 2350);
WIRE 16 -1 (4300 2350)(4300 2800);
WIRE 16 -1 (4300 2350)(4950 2350);
FORCEPROP 2 LAST SIG_NAME PWRGD_PVDDQ_ABC
J 0
(4360 2365);
DISPLAY 0.617021 (4360 2365);
PAINT ORANGE (4360 2365);
WIRE 16 -1 (4100 2050)(4300 2050);
WIRE 16 -1 (4300 2050)(4300 2350);
WIRE 16 -1 (4100 1700)(4300 1700);
WIRE 16 -1 (4300 1700)(4300 1650);
WIRE 16 -1 (4300 1700)(4300 2050);
WIRE 16 -1 (4950 1850)(2725 1850);
FORCEPROP 2 LAST SIG_NAME SMB_VR_STBY_LVC3_SCL
J 0
(3810 1865);
DISPLAY 0.617021 (3810 1865);
PAINT ORANGE (3810 1865);
WIRE 16 -1 (4950 1800)(2725 1800);
FORCEPROP 2 LAST SIG_NAME SMB_VR_STBY_LVC3_SDA
J 0
(3810 1815);
DISPLAY 0.617021 (3810 1815);
PAINT ORANGE (3810 1815);
WIRE 16 -1 (4950 1550)(2725 1550);
FORCEPROP 2 LAST SIG_NAME VR_PVDDQ_ABC_VD12
J 0
(4260 1565);
DISPLAY 0.617021 (4260 1565);
PAINT ORANGE (4260 1565);
WIRE 3 682 (4250 3100)(4250 2700);
WIRE 3 682 (4600 3100)(4250 3100);
WIRE 3 682 (4250 2700)(4600 2700);
WIRE 3 682 (4600 2700)(4600 3100);
WIRE 16 -1 (2375 3000)(2375 3050);
WIRE 16 -1 (1975 3000)(1975 3050);
WIRE 16 -1 (2375 3050)(1975 3050);
FORCEPROP 2 LAST SIG_NAME VR_PVDDQ_ABC_VDD
J 0
(1935 3065);
DISPLAY 0.617021 (1935 3065);
PAINT ORANGE (1935 3065);
FORCEPROP 2 LASTPROP $XRERR UNIQUE?
J 0
(1695 3065);
DISPLAY 0.638298 (1695 3065);
PAINT MONO (1695 3065);
DISPLAY INVISIBLE (1695 3065);
WIRE 16 -1 (1825 2350)(1675 2350);
WIRE 16 -1 (1675 3050)(1675 2350);
WIRE 16 -1 (1975 3050)(1675 3050);
WIRE 16 -1 (1675 3150)(1675 3050);
WIRE 16 -1 (2950 2250)(2725 2250);
WIRE 16 -1 (3875 2250)(2950 2250);
FORCEPROP 2 LAST SIG_NAME IRQ_PVDDQ_ABC_VRHOT_LVT3_R_N
J 0
(2810 2265);
DISPLAY 0.617021 (2810 2265);
PAINT ORANGE (2810 2265);
FORCEPROP 2 LASTPROP $XRERR UNIQUE?
J 0
(2570 2265);
DISPLAY 0.638298 (2570 2265);
PAINT MONO (2570 2265);
DISPLAY INVISIBLE (2570 2265);
WIRE 16 -1 (2950 2800)(2950 2250);
WIRE 16 -1 (3700 2600)(3800 2600);
WIRE 16 -1 (3800 2350)(3800 1150);
WIRE 16 -1 (3950 2350)(3800 2350);
WIRE 16 -1 (3700 2350)(3800 2350);
WIRE 16 -1 (3700 2350)(3700 2600);
WIRE 16 -1 (2725 2350)(3300 2350);
FORCEPROP 2 LAST SIG_NAME PWRGD_PVDDQ_ABC_R
J 0
(3210 2365);
DISPLAY 0.617021 (3210 2365);
PAINT ORANGE (3210 2365);
WIRE 16 -1 (3300 2350)(3700 2350);
WIRE 16 -1 (3300 2800)(3300 2350);
WIRE 3 682 (1000 -350)(1750 -350);
WIRE 3 682 (1000 150)(1000 -350);
WIRE 3 682 (1750 -350)(1750 150);
WIRE 3 682 (1750 150)(1000 150);
WIRE 16 -1 (1400 750)(1825 750);
WIRE 16 -1 (1400 50)(1400 750);
FORCEPROP 0 LAST SIG_NAME VR_PVDDQ_ABC_XADDR2
R 1
J 0
(1390 185);
DISPLAY 0.617021 (1390 185);
PAINT ORANGE (1390 185);
FORCEPROP 2 LASTPROP $XRERR UNIQUE?
J 0
(1150 185);
DISPLAY 0.638298 (1150 185);
PAINT MONO (1150 185);
DISPLAY INVISIBLE (1150 185);
WIRE 16 -1 (3150 300)(3150 375);
WIRE 16 -1 (3550 375)(3150 375);
FORCEPROP 2 LAST SIG_NAME VR_PVDDQ_ABC_VD12
J 0
(3235 390);
DISPLAY 0.617021 (3235 390);
PAINT ORANGE (3235 390);
WIRE 16 -1 (3550 300)(3550 375);
WIRE 16 -1 (3550 375)(4050 375);
WIRE 16 -1 (2725 1500)(3525 1500);
FORCEPROP 2 LAST SIG_NAME SVID_VDIO_PVDDQ_ABC
J 0
(2825 1515);
DISPLAY 0.617021 (2825 1515);
PAINT ORANGE (2825 1515);
FORCEPROP 2 LASTPROP $XRERR UNIQUE?
J 0
(2585 1515);
DISPLAY 0.638298 (2585 1515);
PAINT MONO (2585 1515);
DISPLAY INVISIBLE (2585 1515);
WIRE 16 -1 (1050 800)(1825 800);
WIRE 16 -1 (1050 50)(1050 800);
FORCEPROP 0 LAST SIG_NAME VR_PVDDQ_ABC_XADDR1
R 1
J 0
(1040 210);
DISPLAY 0.617021 (1040 210);
PAINT ORANGE (1040 210);
FORCEPROP 2 LASTPROP $XRERR UNIQUE?
J 0
(800 210);
DISPLAY 0.638298 (800 210);
PAINT MONO (800 210);
DISPLAY INVISIBLE (800 210);
WIRE 3 682 (1700 950)(1750 950);
WIRE 3 682 (1700 1050)(1700 950);
WIRE 3 682 (1750 1050)(1700 1050);
WIRE 3 682 (1750 1150)(1700 1150);
WIRE 3 682 (1700 1150)(1700 1050);
WIRE 3 682 (175 -50)(650 -50);
WIRE 3 682 (175 400)(175 -50);
WIRE 3 682 (650 -50)(650 400);
WIRE 3 682 (650 400)(175 400);
WIRE 16 -1 (-675 1025)(-1350 1025);
FORCEPROP 2 LAST SIG_NAME VSENSE_PVDDQ_ABC_P
J 0
(-1365 1040);
DISPLAY 0.617021 (-1365 1040);
PAINT ORANGE (-1365 1040);
WIRE 16 -1 (-1350 1300)(-525 1300);
FORCEPROP 2 LAST SIG_NAME FM_PVDDQ_ABC_EN
J 0
(-1325 1310);
DISPLAY 0.617021 (-1325 1310);
PAINT ORANGE (-1325 1310);
WIRE 16 -1 (3375 2200)(2725 2200);
FORCEPROP 2 LAST SIG_NAME SVID_ALERT_PVDDQ_ABC
J 0
(2825 2215);
DISPLAY 0.617021 (2825 2215);
PAINT ORANGE (2825 2215);
FORCEPROP 2 LASTPROP $XRERR UNIQUE?
J 0
(2585 2215);
DISPLAY 0.638298 (2585 2215);
PAINT MONO (2585 2215);
DISPLAY INVISIBLE (2585 2215);
WIRE 3 682 (300 3500)(300 3100);
WIRE 3 682 (800 3500)(300 3500);
WIRE 3 682 (300 3100)(800 3100);
WIRE 3 682 (800 3100)(800 3500);
WIRE 3 682 (2850 1000)(2800 1000);
WIRE 3 682 (2850 1050)(2850 1000);
WIRE 3 682 (2800 1050)(2850 1050);
WIRE 3 682 (2850 1050)(2900 1050);
WIRE 16 -1 (4950 2250)(4075 2250);
FORCEPROP 2 LAST SIG_NAME IRQ_PVDDQ_ABC_VRHOT_LVT3_N
J 0
(4335 2265);
DISPLAY 0.617021 (4335 2265);
PAINT ORANGE (4335 2265);
WIRE 16 -1 (2725 1250)(4950 1250);
FORCEPROP 2 LAST SIG_NAME VR_PVDDQ_ABC_PWM2
J 0
(4250 1265);
DISPLAY 0.617021 (4250 1265);
PAINT ORANGE (4250 1265);
WIRE 3 2175 (-1800 2475)(-1175 2475);
WIRE 3 2175 (-1175 2475)(-1175 2725);
WIRE 3 2175 (-1800 2475)(-1800 2725);
WIRE 3 2175 (-1800 2725)(-1175 2725);
WIRE 16 -1 (2725 2050)(3900 2050);
FORCEPROP 2 LAST SIG_NAME TP_PVDDQ_ABC_MP2
J 0
(2825 2065);
DISPLAY 0.617021 (2825 2065);
PAINT ORANGE (2825 2065);
FORCEPROP 2 LASTPROP $XRERR UNIQUE?
J 0
(2585 2065);
DISPLAY 0.638298 (2585 2065);
PAINT MONO (2585 2065);
DISPLAY INVISIBLE (2585 2065);
WIRE 3 682 (4900 1650)(4850 1650);
WIRE 3 682 (4900 1700)(4850 1700);
WIRE 3 682 (4900 1700)(4900 1650);
WIRE 3 682 (4900 2050)(4900 1700);
WIRE 3 682 (4900 2050)(4350 2050);
WIRE 3 682 (4900 2050)(4950 2050);
WIRE 16 -1 (3575 2200)(4950 2200);
FORCEPROP 2 LAST SIG_NAME SVID_ALERT1_CPU0_R_N
J 0
(4350 2210);
DISPLAY 0.617021 (4350 2210);
PAINT ORANGE (4350 2210);
WIRE 3 682 (3700 1900)(3500 1900);
WIRE 3 682 (3700 1750)(3700 1900);
WIRE 3 682 (3500 1900)(3500 1750);
WIRE 3 682 (3500 1750)(3700 1750);
WIRE 16 -1 (3900 1700)(2725 1700);
FORCEPROP 2 LAST SIG_NAME PU_VR_PVDDQ_ABC_FAULT1
J 0
(2835 1715);
DISPLAY 0.617021 (2835 1715);
PAINT ORANGE (2835 1715);
FORCEPROP 2 LASTPROP $XRERR UNIQUE?
J 0
(2595 1715);
DISPLAY 0.638298 (2595 1715);
PAINT MONO (2595 1715);
DISPLAY INVISIBLE (2595 1715);
WIRE 16 -1 (2725 1650)(3900 1650);
FORCEPROP 2 LAST SIG_NAME TP_PVDDQ_ABC_MP1
J 0
(2825 1665);
DISPLAY 0.617021 (2825 1665);
PAINT ORANGE (2825 1665);
FORCEPROP 2 LASTPROP $XRERR UNIQUE?
J 0
(2585 1665);
DISPLAY 0.638298 (2585 1665);
PAINT MONO (2585 1665);
DISPLAY INVISIBLE (2585 1665);
WIRE 16 -1 (1825 1200)(400 1200);
WIRE 16 -1 (400 675)(400 1200);
WIRE 16 -1 (-300 675)(-1350 675);
FORCEPROP 2 LAST SIG_NAME VSENSE_PVDDQ_ABC_N
J 0
(-1365 690);
DISPLAY 0.617021 (-1365 690);
PAINT ORANGE (-1365 690);
WIRE 16 -1 (-300 750)(-300 675);
WIRE 16 -1 (-300 675)(400 675);
WIRE 16 -1 (1825 1450)(250 1450);
WIRE 16 -1 (250 1025)(250 1450);
WIRE 16 -1 (-300 950)(-300 1025);
WIRE 16 -1 (-475 1025)(-300 1025);
WIRE 16 -1 (-300 1025)(250 1025);
FORCEPROP 2 LAST SIG_NAME VR_PVDDQ_ABC_AVSP
J 0
(-240 1040);
DISPLAY 0.617021 (-240 1040);
PAINT ORANGE (-240 1040);
FORCEPROP 2 LASTPROP $XRERR UNIQUE?
J 0
(-480 1040);
DISPLAY 0.638298 (-480 1040);
PAINT MONO (-480 1040);
DISPLAY INVISIBLE (-480 1040);
WIRE 16 -1 (875 650)(875 1600);
WIRE 16 -1 (875 1600)(1825 1600);
WIRE 16 -1 (-1350 1600)(875 1600);
FORCEPROP 2 LAST SIG_NAME A_TSENSE_PVDDQ_ABC
J 0
(-1375 1615);
DISPLAY 0.617021 (-1375 1615);
PAINT ORANGE (-1375 1615);
WIRE 3 682 (-550 2400)(-800 2400);
WIRE 3 682 (-800 2400)(-800 2750);
WIRE 3 682 (-550 2700)(-550 2400);
WIRE 3 682 (350 2700)(-550 2700);
WIRE 3 682 (-800 2750)(350 2750);
WIRE 3 682 (350 2750)(350 2700);
WIRE 3 2175 (-500 2200)(50 2200);
WIRE 3 2175 (50 2200)(50 2650);
WIRE 3 2175 (-500 2200)(-500 2650);
WIRE 3 2175 (-500 2650)(50 2650);
WIRE 16 -1 (575 2800)(450 2800);
WIRE 16 -1 (450 3225)(450 2800);
WIRE 16 -1 (-1350 2800)(450 2800);
FORCEPROP 0 LAST SIG_NAME SVID_CLK1_CPU0_R
J 0
(-1350 2810);
DISPLAY 0.617021 (-1350 2810);
PAINT ORANGE (-1350 2810);
WIRE 16 -1 (-325 1300)(975 1300);
WIRE 16 -1 (975 1300)(1825 1300);
FORCEPROP 2 LAST SIG_NAME VR_PVDDQ_ABC_VREN
J 0
(1100 1310);
DISPLAY 0.617021 (1100 1310);
PAINT ORANGE (1100 1310);
FORCEPROP 2 LASTPROP $XRERR UNIQUE?
J 0
(860 1310);
DISPLAY 0.638298 (860 1310);
PAINT MONO (860 1310);
DISPLAY INVISIBLE (860 1310);
WIRE 16 -1 (975 1300)(975 3225);
WIRE 16 -1 (1500 2250)(1825 2250);
WIRE 16 -1 (775 2800)(1500 2800);
FORCEPROP 2 LAST SIG_NAME SVID_CLK_PVDDQ_ABC
J 0
(1035 2815);
DISPLAY 0.617021 (1035 2815);
PAINT ORANGE (1035 2815);
FORCEPROP 2 LASTPROP $XRERR UNIQUE?
J 0
(795 2815);
DISPLAY 0.638298 (795 2815);
PAINT MONO (795 2815);
DISPLAY INVISIBLE (795 2815);
WIRE 16 -1 (1500 2800)(1500 2250);
WIRE 16 -1 (-1350 1950)(25 1950);
WIRE 16 -1 (25 1950)(1825 1950);
WIRE 16 -1 (-200 2325)(25 2325);
WIRE 16 -1 (25 2325)(25 1950);
WIRE 16 -1 (-150 2525)(25 2525);
WIRE 16 -1 (25 2525)(25 2325);
WIRE 16 -1 (550 2600)(450 2600);
WIRE 16 -1 (450 2600)(450 2450);
WIRE 16 -1 (550 2450)(450 2450);
WIRE 16 -1 (-1350 2100)(450 2100);
FORCEPROP 2 LAST SIG_NAME VR_PVDDQ_ABC_AIREF2
J 0
(-1340 2115);
DISPLAY 0.617021 (-1340 2115);
PAINT ORANGE (-1340 2115);
WIRE 16 -1 (450 2100)(450 2450);
WIRE 16 -1 (1825 2100)(450 2100);
WIRE 16 -1 (-350 2525)(-450 2525);
WIRE 16 -1 (-450 2525)(-450 2325);
WIRE 16 -1 (-350 2325)(-450 2325);
WIRE 16 -1 (-450 2325)(-450 2150);
WIRE 16 -1 (-450 2150)(1825 2150);
WIRE 16 -1 (-1350 2150)(-450 2150);
FORCEPROP 2 LAST SIG_NAME VR_PVDDQ_ABC_AIREF1
J 0
(-1340 2165);
DISPLAY 0.617021 (-1340 2165);
PAINT ORANGE (-1340 2165);
WIRE 16 -1 (-1350 1700)(1825 1700);
FORCEPROP 2 LAST SIG_NAME VR_PVDDQ_ABC_AIINSEN
J 0
(-1360 1710);
DISPLAY 0.617021 (-1360 1710);
PAINT ORANGE (-1360 1710);
WIRE 16 -1 (1825 1750)(-1350 1750);
FORCEPROP 2 LAST SIG_NAME VR_PVDDQ_ABC_VINSEN
J 0
(-1375 1765);
DISPLAY 0.617021 (-1375 1765);
PAINT ORANGE (-1375 1765);
WIRE 16 -1 (750 2600)(900 2600);
WIRE 16 -1 (700 2450)(900 2450);
WIRE 16 -1 (900 2600)(900 2450);
WIRE 16 -1 (900 1900)(1825 1900);
WIRE 16 -1 (900 1900)(900 2450);
WIRE 16 -1 (-1350 1900)(900 1900);
WIRE 3 2175 (400 2775)(1200 2775);
WIRE 3 2175 (1200 2050)(1200 2775);
WIRE 3 2175 (400 2050)(400 2775);
WIRE 3 2175 (400 2050)(1200 2050);
DOT 1 (450 2450);
DOT 1 (900 2450);
DOT 1 (-300 1025);
DOT 1 (4300 2350);
DOT 1 (25 2325);
DOT 1 (2850 800);
DOT 1 (3800 2350);
DOT 1 (1700 1050);
DOT 1 (2850 1050);
DOT 1 (-300 675);
DOT 1 (25 1950);
DOT 1 (-450 2150);
DOT 1 (-450 2325);
DOT 1 (450 2100);
DOT 1 (975 1300);
DOT 1 (875 1600);
DOT 1 (900 1900);
DOT 1 (1675 3050);
DOT 1 (1975 3050);
DOT 1 (1675 3575);
DOT 1 (3550 375);
DOT 1 (2950 2250);
DOT 1 (3300 2350);
DOT 1 (3300 3350);
DOT 1 (3500 3350);
DOT 1 (3700 2350);
DOT 1 (4900 1700);
DOT 1 (450 2800);
DOT 1 (4300 1700);
DOT 1 (4900 2050);
DOT 1 (4750 1500);
DOT 1 (4300 2050);
FORCENOTE
TP FAB1 NC 0321
(1350 2050) 0;
DISPLAY LEFT (1350 2050);
DISPLAY 0.638298 (1350 2050);
PAINT RED (1350 2050);
FORCENOTE
TP FAB4 CHANGE RF15 TO 909OHM FOR VR FAILCHILD, SINGLE SIDE BOM 20170123
(-1275 2750) 0;
DISPLAY LEFT (-1275 2750);
DISPLAY 0.638298 (-1275 2750);
PAINT RED (-1275 2750);
FORCENOTE
TP FAB1 NC 0321
(1075 1825) 0;
DISPLAY LEFT (1075 1825);
DISPLAY 1.021277 (1075 1825);
PAINT RED (1075 1825);
FORCENOTE
TP FAB1 NC 0321
(1000 1125) 0;
DISPLAY LEFT (1000 1125);
DISPLAY 1.021277 (1000 1125);
PAINT RED (1000 1125);
FORCENOTE
TP FAB1 NC 0321
(1075 1525) 0;
DISPLAY LEFT (1075 1525);
DISPLAY 1.021277 (1075 1525);
PAINT RED (1075 1525);
FORCENOTE
INFINEON:NOPOP
(-1750 2550) 0;
DISPLAY LEFT (-1750 2550);
DISPLAY 0.872340 (-1750 2550);
PAINT RED (-1750 2550);
FORCENOTE
FAIRCHILD:POP
(-1750 2500) 0;
DISPLAY LEFT (-1750 2500);
DISPLAY 0.872340 (-1750 2500);
PAINT RED (-1750 2500);
FORCENOTE
CF15&CF16
(-1750 2600) 0;
DISPLAY LEFT (-1750 2600);
DISPLAY 0.872340 (-1750 2600);
PAINT RED (-1750 2600);
FORCENOTE
RF15&RF16
(-1750 2650) 0;
DISPLAY LEFT (-1750 2650);
DISPLAY 0.872340 (-1750 2650);
PAINT RED (-1750 2650);
FORCENOTE
TP FAB1 DELETE RES 0203
(-1150 2250) 0;
DISPLAY LEFT (-1150 2250);
DISPLAY 0.638298 (-1150 2250);
PAINT RED (-1150 2250);
FORCENOTE
ROOM=VDDQ_ABC_PWR_VR
(-1755 -965) 0;
DISPLAY LEFT (-1755 -965);
DISPLAY 2.446809 (-1755 -965);
PAINT PURPLE (-1755 -965);
FORCENOTE
TP FAB3 POP R12W25 0919
(5000 2000) 0;
DISPLAY LEFT (5000 2000);
DISPLAY 0.638298 (5000 2000);
PAINT RED (5000 2000);
FORCENOTE
TP FAB1 NC 0321
(2800 1975) 0;
DISPLAY LEFT (2800 1975);
DISPLAY 1.021277 (2800 1975);
PAINT RED (2800 1975);
FORCENOTE
TP FAB1 DEL NETS 0309
(2950 1000) 0;
DISPLAY LEFT (2950 1000);
DISPLAY 1.021277 (2950 1000);
PAINT RED (2950 1000);
FORCENOTE
TP FAB1 NC 0321
(2800 1200) 0;
DISPLAY LEFT (2800 1200);
DISPLAY 1.021277 (2800 1200);
PAINT RED (2800 1200);
FORCENOTE
TP FAB1 CHANGE R7G8 RES AND NOPOP R7G10 0408
(1000 -425) 0;
DISPLAY LEFT (1000 -425);
DISPLAY 1.021277 (1000 -425);
PAINT RED (1000 -425);
FORCENOTE
TP FAB1 CHANGE R7G8 RES 0523
(1000 -475) 0;
DISPLAY LEFT (1000 -475);
DISPLAY 1.021277 (1000 -475);
PAINT RED (1000 -475);
FORCENOTE
TP FAB3 NOPOP R7G8 AND CHANGE R7G10 0804
(1000 -525) 0;
DISPLAY LEFT (1000 -525);
DISPLAY 1.021277 (1000 -525);
PAINT RED (1000 -525);
FORCENOTE
TP FAB1 NC 0321
(1075 1400) 0;
DISPLAY LEFT (1075 1400);
DISPLAY 1.021277 (1075 1400);
PAINT RED (1075 1400);
FORCENOTE
TP FAB1 POP RES 0316
(-50 3525) 0;
DISPLAY LEFT (-50 3525);
DISPLAY 1.021277 (-50 3525);
PAINT RED (-50 3525);
FORCENOTE
TP FAB1 DEL CAP 0218
(25 -125) 0;
DISPLAY LEFT (25 -125);
DISPLAY 1.021277 (25 -125);
PAINT RED (25 -125);
FORCENOTE
TP FAB1 ADD RES 0303
(5000 2050) 0;
DISPLAY LEFT (5000 2050);
DISPLAY 0.638298 (5000 2050);
PAINT RED (5000 2050);
FORCENOTE
TP FAB3 POP R7F36 1014
(4250 3125) 0;
DISPLAY LEFT (4250 3125);
DISPLAY 0.638298 (4250 3125);
PAINT RED (4250 3125);
FORCENOTE
TP FAB1 NC 0321
(2800 1350) 0;
DISPLAY LEFT (2800 1350);
DISPLAY 1.021277 (2800 1350);
PAINT RED (2800 1350);
FORCENOTE
TP FAB3 NOPOP R7F24 0919
(3775 2525) 0;
DISPLAY LEFT (3775 2525);
DISPLAY 0.638298 (3775 2525);
PAINT RED (3775 2525);
FORCENOTE
TP FAB4 NOPOP RF16 AND CF16 FOR SS BOM 20170124
(400 2000) 0;
DISPLAY LEFT (400 2000);
DISPLAY 0.638298 (400 2000);
PAINT RED (400 2000);
FORCENOTE
TP FAB1 CO-LAY WITH FAIRCHILD PARTS 1203
(-512 2156) 0;
DISPLAY LEFT (-512 2156);
DISPLAY 0.638298 (-512 2156);
PAINT RED (-512 2156);
FORCENOTE
VOUT = 1.2V 
(4775 3425) 0;
DISPLAY LEFT (4775 3425);
DISPLAY 0.808511 (4775 3425);
PAINT PURPLE (4775 3425);
FORCENOTE
TP FAB1 DEL RES 0314
(3375 1925) 0;
DISPLAY LEFT (3375 1925);
DISPLAY 1.021277 (3375 1925);
PAINT RED (3375 1925);
FORCENOTE
SW FREQ = 833.33KHZ
(4775 3025) 0;
DISPLAY LEFT (4775 3025);
DISPLAY 0.808511 (4775 3025);
PAINT PURPLE (4775 3025);
FORCENOTE
IOUT DI/DT = 15A/US/18.09A/US FOR DS/SS
(4775 3075) 0;
DISPLAY LEFT (4775 3075);
DISPLAY 0.808511 (4775 3075);
PAINT PURPLE (4775 3075);
FORCENOTE
IOUT STEP = 45A/17.96A FOR DS/SS
(4775 3125) 0;
DISPLAY LEFT (4775 3125);
DISPLAY 0.808511 (4775 3125);
PAINT PURPLE (4775 3125);
FORCENOTE
IOUT PK = 73A/29.38A FOR DS/SS
(4775 3175) 0;
DISPLAY LEFT (4775 3175);
DISPLAY 0.808511 (4775 3175);
PAINT PURPLE (4775 3175);
FORCENOTE
IOUT TDC = 65.7A/25.86A FOR DS/SS
(4775 3225) 0;
DISPLAY LEFT (4775 3225);
DISPLAY 0.808511 (4775 3225);
PAINT PURPLE (4775 3225);
FORCENOTE
AC & RIPPLE TOL = +/2.8%
(4775 3275) 0;
DISPLAY LEFT (4775 3275);
DISPLAY 0.808511 (4775 3275);
PAINT PURPLE (4775 3275);
FORCENOTE
DC TOL = +/-0.5%
(4775 3325) 0;
DISPLAY LEFT (4775 3325);
DISPLAY 0.808511 (4775 3325);
PAINT PURPLE (4775 3325);
FORCENOTE
RIPPLE GUIDELINE = +/- 0.5%
(4775 3375) 0;
DISPLAY LEFT (4775 3375);
DISPLAY 0.808511 (4775 3375);
PAINT PURPLE (4775 3375);
QUIT
